FILE_TYPE = MACRO_DRAWING;
SET COLOR_WIRE YELLOW;
SET COLOR_PROP ORANGE;
SET COLOR_DOT WHITE;
SET COLOR_ARC YELLOW;
SET COLOR_BODY GREEN;
SET COLOR_NOTE PURPLE;
SET PROP_DISPLAY VALUE;
SET PAGE_NUMBER P143;
FORCEADD OFFPAGE..2
(1150 4050);
FORCEPROP 2 LAST $XR0 215 
J 0
(1339 4050);
DISPLAY 0.638298 (1339 4050);
PAINT MONO (1339 4050);
FORCEPROP 2 LAST PATH I1
J 0
(1350 4100);
DISPLAY 1.021277 (1350 4100);
DISPLAY INVISIBLE (1350 4100);
FORCEPROP 2 LAST CDS_LIB standard
J 0
(1150 4050);
DISPLAY INVISIBLE (1150 4050);
FORCEPROP 1 LAST COMMENT_BODY TRUE
J 0
(1105 3955);
DISPLAY 0.872340 (1105 3955);
PAINT GREEN (1105 3955);
DISPLAY INVISIBLE (1105 3955);
FORCEPROP 1 LAST OFFPAGE TRUE
J 0
(1475 3925);
DISPLAY 0.872340 (1475 3925);
PAINT AQUA (1475 3925);
DISPLAY INVISIBLE (1475 3925);
FORCEADD UNIVERSAL_GND..1
(-1125 3125);
FORCEPROP 3 LASTPIN (-1125 3175) SIG_NAME GND\g
J 0
(-1115 3185);
DISPLAY 0.659574 (-1115 3185);
PAINT MONO (-1115 3185);
DISPLAY INVISIBLE (-1115 3185);
FORCEPROP 1 LAST PATH I10
J 0
(-1050 3125);
DISPLAY 0.872340 (-1050 3125);
PAINT AQUA (-1050 3125);
DISPLAY INVISIBLE (-1050 3125);
FORCEPROP 2 LAST CDS_LIB logical_power
J 0
(-1125 3125);
DISPLAY INVISIBLE (-1125 3125);
FORCEPROP 1 LAST HDL_POWER GND
J 1
(-1100 3050);
DISPLAY 0.872340 (-1100 3050);
PAINT GREEN (-1100 3050);
DISPLAY INVISIBLE (-1100 3050);
FORCEADD Q_RES..2
(-1050 -275);
FORCEPROP 1 LAST PART_NUMBER CS24702JB10
J 0
(-1010 -450);
DISPLAY 0.638298 (-1010 -450);
DISPLAY INVISIBLE (-1010 -450);
FORCEPROP 1 LAST WATTAGE 1/16W
J 0
(-1010 -300);
DISPLAY 0.638298 (-1010 -300);
FORCEPROP 1 LAST MATERIAL CHIP
J 0
(-1010 -350);
DISPLAY 0.638298 (-1010 -350);
FORCEPROP 1 LAST TOLERANCE 5%
J 0
(-1005 -250);
DISPLAY 0.638298 (-1005 -250);
FORCEPROP 1 LAST VALUE 4.7K
J 0
(-1005 -200);
DISPLAY 0.638298 (-1005 -200);
FORCEPROP 1 LAST PACK_TYPE 0402LF
J 0
(-1010 -400);
DISPLAY 0.638298 (-1010 -400);
FORCEPROP 1 LAST $LOCATION R4155
J 0
(-1005 -150);
DISPLAY 0.638298 (-1005 -150);
FORCEPROP 1 LASTPIN (-1050 -175) $PN 1
J 0
(-1045 -213);
DISPLAY 0.787234 (-1045 -213);
FORCEPROP 1 LASTPIN (-1050 -375) $PN 2
J 0
(-1045 -365);
DISPLAY 0.787234 (-1045 -365);
FORCEPROP 1 LAST PATH I100
J 0
(-1000 -100);
DISPLAY 0.978723 (-1000 -100);
PAINT WHITE (-1000 -100);
DISPLAY INVISIBLE (-1000 -100);
FORCEPROP 2 LAST CDS_LIB pure_quanta
J 0
(-1050 -275);
PAINT MONO (-1050 -275);
DISPLAY INVISIBLE (-1050 -275);
FORCEPROP 2 LAST CDS_LOCATION R4155
J 0
(-1000 -50);
DISPLAY 1.021277 (-1000 -50);
DISPLAY INVISIBLE (-1000 -50);
FORCEPROP 2 LAST $SEC 1
J 0
(-1000 -50);
DISPLAY 0.680851 (-1000 -50);
PAINT MONO (-1000 -50);
DISPLAY INVISIBLE (-1000 -50);
FORCEPROP 2 LAST CDS_SEC 1
J 0
(-1000 -50);
DISPLAY 1.021277 (-1000 -50);
DISPLAY INVISIBLE (-1000 -50);
FORCEADD Q_RES..2
(100 -150);
FORCEPROP 1 LAST PART_NUMBER CS24702JB10
J 0
(140 -325);
DISPLAY 0.638298 (140 -325);
DISPLAY INVISIBLE (140 -325);
FORCEPROP 1 LAST WATTAGE 1/16W
J 0
(140 -175);
DISPLAY 0.638298 (140 -175);
FORCEPROP 1 LAST MATERIAL CHIP
J 0
(140 -225);
DISPLAY 0.638298 (140 -225);
FORCEPROP 1 LAST PACK_TYPE 0402LF
J 0
(140 -275);
DISPLAY 0.638298 (140 -275);
FORCEPROP 1 LAST TOLERANCE 5%
J 0
(145 -125);
DISPLAY 0.638298 (145 -125);
FORCEPROP 1 LAST VALUE 4.7K
J 0
(145 -75);
DISPLAY 0.638298 (145 -75);
FORCEPROP 1 LAST $LOCATION R4156
J 0
(145 -25);
DISPLAY 0.638298 (145 -25);
FORCEPROP 1 LASTPIN (100 -50) $PN 1
J 0
(105 -88);
DISPLAY 0.787234 (105 -88);
FORCEPROP 1 LASTPIN (100 -250) $PN 2
J 0
(105 -240);
DISPLAY 0.787234 (105 -240);
FORCEPROP 1 LAST PATH I101
J 0
(150 25);
DISPLAY 0.978723 (150 25);
PAINT WHITE (150 25);
DISPLAY INVISIBLE (150 25);
FORCEPROP 2 LAST CDS_LIB pure_quanta
J 0
(100 -150);
PAINT MONO (100 -150);
DISPLAY INVISIBLE (100 -150);
FORCEPROP 2 LAST CDS_LOCATION R4156
J 0
(150 75);
DISPLAY 1.021277 (150 75);
DISPLAY INVISIBLE (150 75);
FORCEPROP 2 LAST $SEC 1
J 0
(150 75);
DISPLAY 0.680851 (150 75);
PAINT MONO (150 75);
DISPLAY INVISIBLE (150 75);
FORCEPROP 2 LAST CDS_SEC 1
J 0
(150 75);
DISPLAY 1.021277 (150 75);
DISPLAY INVISIBLE (150 75);
FORCEADD OFFPAGE..2
(1225 -325);
FORCEPROP 2 LAST $XR1 227 
J 0
(1534 -325);
DISPLAY 0.638298 (1534 -325);
PAINT MONO (1534 -325);
FORCEPROP 2 LAST $XR0 215 
J 0
(1414 -325);
DISPLAY 0.638298 (1414 -325);
PAINT MONO (1414 -325);
FORCEPROP 2 LAST CDS_LIB standard
J 0
(1225 -325);
DISPLAY INVISIBLE (1225 -325);
FORCEPROP 1 LAST COMMENT_BODY TRUE
J 0
(1180 -420);
DISPLAY 0.872340 (1180 -420);
PAINT GREEN (1180 -420);
DISPLAY INVISIBLE (1180 -420);
FORCEPROP 1 LAST OFFPAGE TRUE
J 0
(1550 -450);
DISPLAY 0.872340 (1550 -450);
PAINT AQUA (1550 -450);
DISPLAY INVISIBLE (1550 -450);
FORCEPROP 2 LAST PATH I102
J 0
(1425 -275);
DISPLAY 1.021277 (1425 -275);
DISPLAY INVISIBLE (1425 -275);
FORCEADD UNIVERSAL_POWER..1
(100 75);
FORCEPROP 3 LASTPIN (100 25) SIG_NAME P3V3_AUX\g
J 0
(110 35);
DISPLAY 0.659574 (110 35);
PAINT MONO (110 35);
DISPLAY INVISIBLE (110 35);
FORCEPROP 1 LAST HDL_POWER P3V3_AUX
J 1
(100 125);
DISPLAY 0.872340 (100 125);
PAINT GREEN (100 125);
FORCEPROP 2 LAST CDS_LIB logical_power
J 0
(100 75);
PAINT MONO (100 75);
DISPLAY INVISIBLE (100 75);
FORCEPROP 1 LAST PATH I103
J 0
(150 100);
DISPLAY 0.872340 (150 100);
PAINT AQUA (150 100);
DISPLAY INVISIBLE (150 100);
FORCEADD UNIVERSAL_GND..1
(875 -825);
FORCEPROP 3 LASTPIN (875 -775) SIG_NAME GND\g
J 0
(885 -765);
DISPLAY 0.659574 (885 -765);
PAINT MONO (885 -765);
DISPLAY INVISIBLE (885 -765);
FORCEPROP 2 LAST CDS_LIB logical_power
J 0
(875 -825);
DISPLAY INVISIBLE (875 -825);
FORCEPROP 1 LAST HDL_POWER GND
J 1
(900 -900);
DISPLAY 0.872340 (900 -900);
PAINT GREEN (900 -900);
DISPLAY INVISIBLE (900 -900);
FORCEPROP 1 LAST PATH I104
J 0
(950 -825);
DISPLAY 0.872340 (950 -825);
PAINT AQUA (950 -825);
DISPLAY INVISIBLE (950 -825);
FORCEADD Q_CAP..1
(875 -625);
FORCEPROP 1 LAST PART_NUMBER TMP_QCH21006JB10
J 0
(925 -775);
DISPLAY 0.638298 (925 -775);
DISPLAY INVISIBLE (925 -775);
FORCEPROP 1 LAST TOLERANCE 5%
J 0
(925 -675);
DISPLAY 0.638298 (925 -675);
FORCEPROP 1 LAST MATERIAL EMPTY
J 0
(925 -725);
DISPLAY 0.638298 (925 -725);
PAINT RED (925 -725);
FORCEPROP 1 LAST VOLTAGE 50V
J 0
(925 -625);
DISPLAY 0.638298 (925 -625);
FORCEPROP 1 LAST VALUE 1000PF
J 0
(925 -575);
DISPLAY 0.638298 (925 -575);
FORCEPROP 1 LAST PACK_TYPE 0402
J 0
(925 -825);
DISPLAY 0.638298 (925 -825);
FORCEPROP 1 LAST $LOCATION C2270
J 0
(925 -525);
DISPLAY 0.978723 (925 -525);
FORCEPROP 1 LASTPIN (875 -525) $PN 1
J 0
(885 -545);
DISPLAY 0.787234 (885 -545);
PAINT MONO (885 -545);
FORCEPROP 1 LASTPIN (875 -725) $PN 2
J 0
(885 -745);
DISPLAY 0.787234 (885 -745);
PAINT MONO (885 -745);
FORCEPROP 1 LAST PATH I105
J 0
(925 -475);
DISPLAY 0.978723 (925 -475);
PAINT WHITE (925 -475);
DISPLAY INVISIBLE (925 -475);
FORCEPROP 2 LAST CDS_LIB pure_quanta
J 0
(875 -625);
DISPLAY INVISIBLE (875 -625);
FORCEPROP 0 LAST CDS_LOCATION C2270
J 0
(925 -475);
DISPLAY 1.021277 (925 -475);
DISPLAY INVISIBLE (925 -475);
FORCEPROP 0 LAST $SEC 1
J 0
(925 -475);
DISPLAY 0.680851 (925 -475);
PAINT MONO (925 -475);
DISPLAY INVISIBLE (925 -475);
FORCEPROP 0 LAST CDS_SEC 1
J 0
(925 -475);
DISPLAY 1.021277 (925 -475);
DISPLAY INVISIBLE (925 -475);
FORCEADD UNIVERSAL_GND..1
(100 -950);
FORCEPROP 3 LASTPIN (100 -900) SIG_NAME GND\g
J 0
(110 -890);
DISPLAY 0.659574 (110 -890);
PAINT MONO (110 -890);
DISPLAY INVISIBLE (110 -890);
FORCEPROP 2 LAST CDS_LIB logical_power
J 0
(100 -950);
DISPLAY INVISIBLE (100 -950);
FORCEPROP 1 LAST HDL_POWER GND
J 1
(125 -1025);
DISPLAY 0.872340 (125 -1025);
PAINT GREEN (125 -1025);
DISPLAY INVISIBLE (125 -1025);
FORCEPROP 1 LAST PATH I106
J 0
(175 -950);
DISPLAY 0.872340 (175 -950);
PAINT AQUA (175 -950);
DISPLAY INVISIBLE (175 -950);
FORCEADD MOSFET_NCH_DUAL..2
(50 -575);
FORCEPROP 1 LAST PART_NUMBER BAM138K0003
J 0
(201 -669);
DISPLAY 0.723404 (201 -669);
PAINT GREEN (201 -669);
DISPLAY INVISIBLE (201 -669);
FORCEPROP 2 LAST VALUE PJT138K
J 0
(225 -550);
DISPLAY 1.021277 (225 -550);
FORCEPROP 1 LAST MATERIAL IC
J 0
(201 -724);
DISPLAY 0.723404 (201 -724);
PAINT GREEN (201 -724);
FORCEPROP 2 LAST PART_TYPE SMLF
J 0
(225 -500);
DISPLAY 1.021277 (225 -500);
FORCEPROP 1 LAST $LOCATION Q134
J 0
(201 -599);
DISPLAY 0.723404 (201 -599);
PAINT GREEN (201 -599);
FORCEPROP 0 LASTPIN (100 -375) $PN 3
R 1
J 0
(90 -365);
DISPLAY 0.680851 (90 -365);
PAINT MONO (90 -365);
FORCEPROP 0 LASTPIN (-150 -625) $PN 5
J 2
(-160 -615);
DISPLAY 0.680851 (-160 -615);
PAINT MONO (-160 -615);
FORCEPROP 0 LASTPIN (100 -775) $PN 4
R 1
J 2
(90 -785);
DISPLAY 0.680851 (90 -785);
PAINT MONO (90 -785);
FORCEPROP 1 LAST PATH I107
J 0
(200 -725);
DISPLAY 0.723404 (200 -725);
PAINT GREEN (200 -725);
DISPLAY INVISIBLE (200 -725);
FORCEPROP 1 LAST CDS_LMAN_SYM_OUTLINE -150,150,150,-150
J 0
(50 -575);
DISPLAY 0.468085 (50 -575);
PAINT GREEN (50 -575);
DISPLAY INVISIBLE (50 -575);
FORCEPROP 1 LAST NEEDS_NO_SIZE TRUE
J 0
(200 -684);
DISPLAY 0.468085 (200 -684);
PAINT GREEN (200 -684);
DISPLAY INVISIBLE (200 -684);
FORCEPROP 2 LAST CDS_LIB pure_quanta
J 0
(50 -575);
DISPLAY INVISIBLE (50 -575);
FORCEPROP 0 LAST CDS_LOCATION Q134
J 0
(225 -450);
DISPLAY 1.021277 (225 -450);
DISPLAY INVISIBLE (225 -450);
FORCEPROP 0 LAST $SEC 2
J 0
(225 -450);
DISPLAY 0.680851 (225 -450);
PAINT MONO (225 -450);
DISPLAY INVISIBLE (225 -450);
FORCEPROP 0 LAST CDS_SEC 2
J 0
(225 -450);
DISPLAY 1.021277 (225 -450);
DISPLAY INVISIBLE (225 -450);
FORCEADD UNIVERSAL_POWER..1
(-1050 -50);
FORCEPROP 3 LASTPIN (-1050 -100) SIG_NAME P3V3_AUX\g
J 0
(-1040 -90);
DISPLAY 0.659574 (-1040 -90);
PAINT MONO (-1040 -90);
DISPLAY INVISIBLE (-1040 -90);
FORCEPROP 1 LAST HDL_POWER P3V3_AUX
J 1
(-1050 0);
DISPLAY 0.872340 (-1050 0);
PAINT GREEN (-1050 0);
FORCEPROP 2 LAST CDS_LIB logical_power
J 0
(-1050 -50);
PAINT MONO (-1050 -50);
DISPLAY INVISIBLE (-1050 -50);
FORCEPROP 1 LAST PATH I108
J 0
(-1000 -25);
DISPLAY 0.872340 (-1000 -25);
PAINT AQUA (-1000 -25);
DISPLAY INVISIBLE (-1000 -25);
FORCEADD UNIVERSAL_GND..1
(-1050 -1250);
FORCEPROP 3 LASTPIN (-1050 -1200) SIG_NAME GND\g
J 0
(-1040 -1190);
DISPLAY 0.659574 (-1040 -1190);
PAINT MONO (-1040 -1190);
DISPLAY INVISIBLE (-1040 -1190);
FORCEPROP 2 LAST CDS_LIB logical_power
J 0
(-1050 -1250);
DISPLAY INVISIBLE (-1050 -1250);
FORCEPROP 1 LAST HDL_POWER GND
J 1
(-1025 -1325);
DISPLAY 0.872340 (-1025 -1325);
PAINT GREEN (-1025 -1325);
DISPLAY INVISIBLE (-1025 -1325);
FORCEPROP 1 LAST PATH I109
J 0
(-975 -1250);
DISPLAY 0.872340 (-975 -1250);
PAINT AQUA (-975 -1250);
DISPLAY INVISIBLE (-975 -1250);
FORCEADD MOSFET_NCH_DUAL..1
(-1175 3500);
FORCEPROP 1 LAST PART_NUMBER BAM138K0003
J 0
(-1024 3414);
DISPLAY 0.723404 (-1024 3414);
PAINT GREEN (-1024 3414);
DISPLAY INVISIBLE (-1024 3414);
FORCEPROP 1 LAST MATERIAL IC
J 0
(-1024 3349);
DISPLAY 0.723404 (-1024 3349);
PAINT GREEN (-1024 3349);
FORCEPROP 2 LAST VALUE PJT138K
J 0
(-1000 3525);
DISPLAY 1.021277 (-1000 3525);
FORCEPROP 2 LAST PART_TYPE SMLF
J 0
(-1000 3575);
DISPLAY 1.021277 (-1000 3575);
FORCEPROP 1 LAST $LOCATION Q128
J 0
(-1024 3474);
DISPLAY 0.723404 (-1024 3474);
PAINT GREEN (-1024 3474);
FORCEPROP 0 LASTPIN (-1125 3700) $PN 6
R 1
J 0
(-1135 3710);
DISPLAY 0.680851 (-1135 3710);
PAINT MONO (-1135 3710);
FORCEPROP 0 LASTPIN (-1375 3450) $PN 2
J 2
(-1385 3460);
DISPLAY 0.680851 (-1385 3460);
PAINT MONO (-1385 3460);
FORCEPROP 0 LASTPIN (-1125 3300) $PN 1
R 1
J 2
(-1135 3290);
DISPLAY 0.680851 (-1135 3290);
PAINT MONO (-1135 3290);
FORCEPROP 2 LAST CDS_LIB pure_quanta
J 0
(-1175 3500);
DISPLAY INVISIBLE (-1175 3500);
FORCEPROP 1 LAST NEEDS_NO_SIZE TRUE
J 0
(-1175 3499);
DISPLAY 0.468085 (-1175 3499);
PAINT GREEN (-1175 3499);
DISPLAY INVISIBLE (-1175 3499);
FORCEPROP 1 LAST CDS_LMAN_SYM_OUTLINE -150,150,150,-150
J 0
(-1175 3500);
DISPLAY 0.468085 (-1175 3500);
PAINT GREEN (-1175 3500);
DISPLAY INVISIBLE (-1175 3500);
FORCEPROP 1 LAST PATH I11
J 0
(-1175 3500);
DISPLAY 0.723404 (-1175 3500);
PAINT GREEN (-1175 3500);
DISPLAY INVISIBLE (-1175 3500);
FORCEPROP 2 LAST CDS_LOCATION Q128
J 0
(-1000 3625);
DISPLAY 1.021277 (-1000 3625);
DISPLAY INVISIBLE (-1000 3625);
FORCEPROP 0 LAST $SEC 1
J 0
(-1000 3625);
DISPLAY 0.680851 (-1000 3625);
PAINT MONO (-1000 3625);
DISPLAY INVISIBLE (-1000 3625);
FORCEPROP 2 LAST CDS_SEC 1
J 0
(-1000 3625);
DISPLAY 1.021277 (-1000 3625);
DISPLAY INVISIBLE (-1000 3625);
FORCEADD UNIVERSAL_POWER..1
(-2225 -400);
FORCEPROP 3 LASTPIN (-2225 -450) SIG_NAME P3V3_AUX\g
J 0
(-2215 -440);
DISPLAY 0.659574 (-2215 -440);
PAINT MONO (-2215 -440);
DISPLAY INVISIBLE (-2215 -440);
FORCEPROP 1 LAST HDL_POWER P3V3_AUX
J 1
(-2225 -350);
DISPLAY 0.872340 (-2225 -350);
PAINT GREEN (-2225 -350);
FORCEPROP 2 LAST CDS_LIB logical_power
J 0
(-2225 -400);
PAINT MONO (-2225 -400);
DISPLAY INVISIBLE (-2225 -400);
FORCEPROP 1 LAST PATH I110
J 0
(-2175 -375);
DISPLAY 0.872340 (-2175 -375);
PAINT AQUA (-2175 -375);
DISPLAY INVISIBLE (-2175 -375);
FORCEADD OFFPAGE..4
R 2
(-2475 -925);
FORCEPROP 2 LAST $XR0 137 
J 0
(-2727 -925);
DISPLAY 0.638298 (-2727 -925);
PAINT MONO (-2727 -925);
FORCEPROP 1 LAST OFFPAGE TRUE
J 2
(-2800 -1050);
DISPLAY 0.872340 (-2800 -1050);
PAINT GREEN (-2800 -1050);
DISPLAY INVISIBLE (-2800 -1050);
FORCEPROP 1 LAST COMMENT_BODY TRUE
J 2
(-2450 -1025);
DISPLAY 0.872340 (-2450 -1025);
PAINT GREEN (-2450 -1025);
DISPLAY INVISIBLE (-2450 -1025);
FORCEPROP 2 LAST CDS_LIB standard
J 0
(-2475 -925);
DISPLAY INVISIBLE (-2475 -925);
FORCEPROP 2 LAST PATH I112
J 0
(-2750 -875);
DISPLAY 1.021277 (-2750 -875);
DISPLAY INVISIBLE (-2750 -875);
FORCEADD Q_RES..2
(-2200 -1125);
FORCEPROP 1 LAST PART_NUMBER CS41002FB09
J 0
(-2160 -1250);
DISPLAY 0.510638 (-2160 -1250);
DISPLAY INVISIBLE (-2160 -1250);
FORCEPROP 1 LAST TOLERANCE 1%
J 0
(-2155 -1100);
DISPLAY 0.510638 (-2155 -1100);
FORCEPROP 1 LAST VALUE 100K
J 0
(-2155 -1050);
DISPLAY 0.510638 (-2155 -1050);
FORCEPROP 1 LAST PACK_TYPE 0402LF
J 0
(-2160 -1300);
DISPLAY 0.510638 (-2160 -1300);
FORCEPROP 1 LAST MATERIAL EMPTY
J 0
(-2160 -1200);
DISPLAY 0.510638 (-2160 -1200);
PAINT RED (-2160 -1200);
FORCEPROP 1 LAST WATTAGE 1/16W
J 0
(-2160 -1150);
DISPLAY 0.510638 (-2160 -1150);
FORCEPROP 1 LAST $LOCATION R4154
J 0
(-2155 -1000);
DISPLAY 0.978723 (-2155 -1000);
FORCEPROP 1 LASTPIN (-2200 -1025) $PN 1
J 0
(-2195 -1063);
DISPLAY 0.787234 (-2195 -1063);
PAINT MONO (-2195 -1063);
FORCEPROP 1 LASTPIN (-2200 -1225) $PN 2
J 0
(-2195 -1215);
DISPLAY 0.787234 (-2195 -1215);
PAINT MONO (-2195 -1215);
FORCEPROP 1 LAST PATH I113
J 0
(-2150 -950);
DISPLAY 0.978723 (-2150 -950);
PAINT WHITE (-2150 -950);
DISPLAY INVISIBLE (-2150 -950);
FORCEPROP 2 LAST CDS_LIB pure_quanta
J 0
(-2200 -1125);
DISPLAY INVISIBLE (-2200 -1125);
FORCEPROP 0 LAST CDS_LOCATION R4154
J 0
(-2150 -950);
DISPLAY 1.021277 (-2150 -950);
DISPLAY INVISIBLE (-2150 -950);
FORCEPROP 0 LAST $SEC 1
J 0
(-2150 -950);
DISPLAY 0.680851 (-2150 -950);
PAINT MONO (-2150 -950);
DISPLAY INVISIBLE (-2150 -950);
FORCEPROP 0 LAST CDS_SEC 1
J 0
(-2150 -950);
DISPLAY 1.021277 (-2150 -950);
DISPLAY INVISIBLE (-2150 -950);
FORCEADD UNIVERSAL_GND..1
(-2200 -1400);
FORCEPROP 3 LASTPIN (-2200 -1350) SIG_NAME GND\g
J 0
(-2190 -1340);
DISPLAY 0.659574 (-2190 -1340);
PAINT MONO (-2190 -1340);
DISPLAY INVISIBLE (-2190 -1340);
FORCEPROP 1 LAST PATH I114
J 0
(-2125 -1400);
DISPLAY 0.872340 (-2125 -1400);
PAINT AQUA (-2125 -1400);
DISPLAY INVISIBLE (-2125 -1400);
FORCEPROP 2 LAST CDS_LIB logical_power
J 0
(-2200 -1400);
DISPLAY INVISIBLE (-2200 -1400);
FORCEPROP 1 LAST HDL_POWER GND
J 1
(-2175 -1475);
DISPLAY 0.872340 (-2175 -1475);
PAINT GREEN (-2175 -1475);
DISPLAY INVISIBLE (-2175 -1475);
FORCEADD Q_RES..2
(4650 225);
FORCEPROP 1 LAST PART_NUMBER CS24702JB10
J 0
(4690 50);
DISPLAY 0.638298 (4690 50);
DISPLAY INVISIBLE (4690 50);
FORCEPROP 1 LAST WATTAGE 1/16W
J 0
(4690 200);
DISPLAY 0.638298 (4690 200);
FORCEPROP 1 LAST PACK_TYPE 0402LF
J 0
(4690 100);
DISPLAY 0.638298 (4690 100);
FORCEPROP 1 LAST VALUE 4.7K
J 0
(4695 300);
DISPLAY 0.638298 (4695 300);
FORCEPROP 1 LAST TOLERANCE 5%
J 0
(4695 250);
DISPLAY 0.638298 (4695 250);
FORCEPROP 1 LAST MATERIAL CHIP
J 0
(4690 150);
DISPLAY 0.638298 (4690 150);
FORCEPROP 1 LAST $LOCATION R4561
J 0
(4695 350);
DISPLAY 0.638298 (4695 350);
FORCEPROP 1 LASTPIN (4650 325) $PN 1
J 0
(4655 287);
DISPLAY 0.787234 (4655 287);
FORCEPROP 1 LASTPIN (4650 125) $PN 2
J 0
(4655 135);
DISPLAY 0.787234 (4655 135);
FORCEPROP 2 LAST CDS_LIB pure_quanta
J 0
(4650 225);
PAINT MONO (4650 225);
DISPLAY INVISIBLE (4650 225);
FORCEPROP 1 LAST PATH I116
J 0
(4700 400);
DISPLAY 0.978723 (4700 400);
PAINT WHITE (4700 400);
DISPLAY INVISIBLE (4700 400);
FORCEPROP 2 LAST CDS_LOCATION R4561
J 0
(4700 450);
DISPLAY 1.021277 (4700 450);
DISPLAY INVISIBLE (4700 450);
FORCEPROP 2 LAST $SEC 1
J 0
(4700 450);
DISPLAY 0.680851 (4700 450);
PAINT MONO (4700 450);
DISPLAY INVISIBLE (4700 450);
FORCEPROP 2 LAST CDS_SEC 1
J 0
(4700 450);
DISPLAY 1.021277 (4700 450);
DISPLAY INVISIBLE (4700 450);
FORCEADD OFFPAGE..2
(5775 50);
FORCEPROP 2 LAST $XR0 215 
J 0
(5964 50);
DISPLAY 0.638298 (5964 50);
PAINT MONO (5964 50);
FORCEPROP 2 LAST PATH I117
J 0
(5975 100);
DISPLAY 1.021277 (5975 100);
DISPLAY INVISIBLE (5975 100);
FORCEPROP 2 LAST CDS_LIB standard
J 0
(5775 50);
DISPLAY INVISIBLE (5775 50);
FORCEPROP 1 LAST COMMENT_BODY TRUE
J 0
(5730 -45);
DISPLAY 0.872340 (5730 -45);
PAINT GREEN (5730 -45);
DISPLAY INVISIBLE (5730 -45);
FORCEPROP 1 LAST OFFPAGE TRUE
J 0
(6100 -75);
DISPLAY 0.872340 (6100 -75);
PAINT AQUA (6100 -75);
DISPLAY INVISIBLE (6100 -75);
FORCEADD Q_CAP..1
(5425 -250);
FORCEPROP 1 LAST PART_NUMBER TMP_QCH21006JB10
J 0
(5475 -400);
DISPLAY 0.638298 (5475 -400);
DISPLAY INVISIBLE (5475 -400);
FORCEPROP 1 LAST MATERIAL EMPTY
J 0
(5475 -350);
DISPLAY 0.638298 (5475 -350);
PAINT RED (5475 -350);
FORCEPROP 1 LAST VALUE 1000PF
J 0
(5475 -200);
DISPLAY 0.638298 (5475 -200);
FORCEPROP 1 LAST PACK_TYPE 0402
J 0
(5475 -450);
DISPLAY 0.638298 (5475 -450);
FORCEPROP 1 LAST TOLERANCE 5%
J 0
(5475 -300);
DISPLAY 0.638298 (5475 -300);
FORCEPROP 1 LAST VOLTAGE 50V
J 0
(5475 -250);
DISPLAY 0.638298 (5475 -250);
FORCEPROP 1 LAST $LOCATION C2343
J 0
(5475 -150);
DISPLAY 0.978723 (5475 -150);
FORCEPROP 1 LASTPIN (5425 -150) $PN 1
J 0
(5435 -170);
DISPLAY 0.787234 (5435 -170);
PAINT MONO (5435 -170);
FORCEPROP 1 LASTPIN (5425 -350) $PN 2
J 0
(5435 -370);
DISPLAY 0.787234 (5435 -370);
PAINT MONO (5435 -370);
FORCEPROP 2 LAST CDS_LIB pure_quanta
J 0
(5425 -250);
DISPLAY INVISIBLE (5425 -250);
FORCEPROP 1 LAST PATH I118
J 0
(5475 -100);
DISPLAY 0.978723 (5475 -100);
PAINT WHITE (5475 -100);
DISPLAY INVISIBLE (5475 -100);
FORCEPROP 0 LAST CDS_LOCATION C2343
J 0
(5475 -100);
DISPLAY 1.021277 (5475 -100);
DISPLAY INVISIBLE (5475 -100);
FORCEPROP 0 LAST $SEC 1
J 0
(5475 -100);
DISPLAY 0.680851 (5475 -100);
PAINT MONO (5475 -100);
DISPLAY INVISIBLE (5475 -100);
FORCEPROP 0 LAST CDS_SEC 1
J 0
(5475 -100);
DISPLAY 1.021277 (5475 -100);
DISPLAY INVISIBLE (5475 -100);
FORCEADD UNIVERSAL_GND..1
(5425 -450);
FORCEPROP 3 LASTPIN (5425 -400) SIG_NAME GND\g
J 0
(5435 -390);
DISPLAY 0.659574 (5435 -390);
PAINT MONO (5435 -390);
DISPLAY INVISIBLE (5435 -390);
FORCEPROP 1 LAST HDL_POWER GND
J 1
(5450 -525);
DISPLAY 0.872340 (5450 -525);
PAINT GREEN (5450 -525);
DISPLAY INVISIBLE (5450 -525);
FORCEPROP 2 LAST CDS_LIB logical_power
J 0
(5425 -450);
DISPLAY INVISIBLE (5425 -450);
FORCEPROP 1 LAST PATH I119
J 0
(5500 -450);
DISPLAY 0.872340 (5500 -450);
PAINT AQUA (5500 -450);
DISPLAY INVISIBLE (5500 -450);
FORCEADD UNIVERSAL_POWER..1
(-2300 3975);
FORCEPROP 3 LASTPIN (-2300 3925) SIG_NAME P3V3_AUX\g
J 0
(-2290 3935);
DISPLAY 0.659574 (-2290 3935);
PAINT MONO (-2290 3935);
DISPLAY INVISIBLE (-2290 3935);
FORCEPROP 1 LAST HDL_POWER P3V3_AUX
J 1
(-2300 4025);
DISPLAY 0.872340 (-2300 4025);
PAINT GREEN (-2300 4025);
FORCEPROP 1 LAST PATH I12
J 0
(-2250 4000);
DISPLAY 0.872340 (-2250 4000);
PAINT AQUA (-2250 4000);
DISPLAY INVISIBLE (-2250 4000);
FORCEPROP 2 LAST CDS_LIB logical_power
J 0
(-2300 3975);
PAINT MONO (-2300 3975);
DISPLAY INVISIBLE (-2300 3975);
FORCEADD UNIVERSAL_POWER..1
(4650 450);
FORCEPROP 3 LASTPIN (4650 400) SIG_NAME P3V3_AUX\g
J 0
(4660 410);
DISPLAY 0.659574 (4660 410);
PAINT MONO (4660 410);
DISPLAY INVISIBLE (4660 410);
FORCEPROP 1 LAST HDL_POWER P3V3_AUX
J 1
(4650 500);
DISPLAY 0.872340 (4650 500);
PAINT GREEN (4650 500);
FORCEPROP 2 LAST CDS_LIB logical_power
J 0
(4650 450);
PAINT MONO (4650 450);
DISPLAY INVISIBLE (4650 450);
FORCEPROP 1 LAST PATH I120
J 0
(4700 475);
DISPLAY 0.872340 (4700 475);
PAINT AQUA (4700 475);
DISPLAY INVISIBLE (4700 475);
FORCEADD MOSFET_NCH_DUAL..2
(4600 -200);
FORCEPROP 1 LAST PART_NUMBER BAM138K0003
J 0
(4751 -294);
DISPLAY 0.723404 (4751 -294);
PAINT GREEN (4751 -294);
DISPLAY INVISIBLE (4751 -294);
FORCEPROP 1 LAST MATERIAL IC
J 0
(4751 -349);
DISPLAY 0.723404 (4751 -349);
PAINT GREEN (4751 -349);
FORCEPROP 2 LAST VALUE PJT138K
J 0
(4775 -175);
DISPLAY 1.021277 (4775 -175);
FORCEPROP 2 LAST PART_TYPE SMLF
J 0
(4775 -125);
DISPLAY 1.021277 (4775 -125);
FORCEPROP 1 LAST LOCATION Q146
J 0
(4751 -224);
DISPLAY 0.723404 (4751 -224);
PAINT GREEN (4751 -224);
FORCEPROP 0 LASTPIN (4650 0) $PN 3
R 1
J 0
(4640 10);
DISPLAY 0.680851 (4640 10);
PAINT MONO (4640 10);
FORCEPROP 0 LASTPIN (4400 -250) $PN 5
J 2
(4390 -240);
DISPLAY 0.680851 (4390 -240);
PAINT MONO (4390 -240);
FORCEPROP 0 LASTPIN (4650 -400) $PN 4
R 1
J 2
(4640 -410);
DISPLAY 0.680851 (4640 -410);
PAINT MONO (4640 -410);
FORCEPROP 2 LAST CDS_LIB pure_quanta
J 0
(4600 -200);
DISPLAY INVISIBLE (4600 -200);
FORCEPROP 1 LAST NEEDS_NO_SIZE TRUE
J 0
(4750 -309);
DISPLAY 0.468085 (4750 -309);
PAINT GREEN (4750 -309);
DISPLAY INVISIBLE (4750 -309);
FORCEPROP 1 LAST CDS_LMAN_SYM_OUTLINE -150,150,150,-150
J 0
(4600 -200);
DISPLAY 0.468085 (4600 -200);
PAINT GREEN (4600 -200);
DISPLAY INVISIBLE (4600 -200);
FORCEPROP 1 LAST PATH I121
J 0
(4750 -350);
DISPLAY 0.723404 (4750 -350);
PAINT GREEN (4750 -350);
DISPLAY INVISIBLE (4750 -350);
FORCEPROP 0 LAST $SEC 2
J 0
(4775 -75);
DISPLAY 0.680851 (4775 -75);
PAINT MONO (4775 -75);
DISPLAY INVISIBLE (4775 -75);
FORCEPROP 0 LAST CDS_SEC 2
J 0
(4775 -75);
DISPLAY 1.021277 (4775 -75);
DISPLAY INVISIBLE (4775 -75);
FORCEADD UNIVERSAL_GND..1
(4650 -575);
FORCEPROP 3 LASTPIN (4650 -525) SIG_NAME GND\g
J 0
(4660 -515);
DISPLAY 0.659574 (4660 -515);
PAINT MONO (4660 -515);
DISPLAY INVISIBLE (4660 -515);
FORCEPROP 1 LAST HDL_POWER GND
J 1
(4675 -650);
DISPLAY 0.872340 (4675 -650);
PAINT GREEN (4675 -650);
DISPLAY INVISIBLE (4675 -650);
FORCEPROP 2 LAST CDS_LIB logical_power
J 0
(4650 -575);
DISPLAY INVISIBLE (4650 -575);
FORCEPROP 1 LAST PATH I122
J 0
(4725 -575);
DISPLAY 0.872340 (4725 -575);
PAINT AQUA (4725 -575);
DISPLAY INVISIBLE (4725 -575);
FORCEADD UNIVERSAL_POWER..1
(3500 325);
FORCEPROP 3 LASTPIN (3500 275) SIG_NAME P3V3_AUX\g
J 0
(3510 285);
DISPLAY 0.659574 (3510 285);
PAINT MONO (3510 285);
DISPLAY INVISIBLE (3510 285);
FORCEPROP 1 LAST HDL_POWER P3V3_AUX
J 1
(3500 375);
DISPLAY 0.872340 (3500 375);
PAINT GREEN (3500 375);
FORCEPROP 2 LAST CDS_LIB logical_power
J 0
(3500 325);
PAINT MONO (3500 325);
DISPLAY INVISIBLE (3500 325);
FORCEPROP 1 LAST PATH I123
J 0
(3550 350);
DISPLAY 0.872340 (3550 350);
PAINT AQUA (3550 350);
DISPLAY INVISIBLE (3550 350);
FORCEADD Q_RES..2
(3500 100);
FORCEPROP 1 LAST PART_NUMBER CS24702JB10
J 0
(3540 -75);
DISPLAY 0.638298 (3540 -75);
DISPLAY INVISIBLE (3540 -75);
FORCEPROP 1 LAST PACK_TYPE 0402LF
J 0
(3540 -25);
DISPLAY 0.638298 (3540 -25);
FORCEPROP 1 LAST WATTAGE 1/16W
J 0
(3540 75);
DISPLAY 0.638298 (3540 75);
FORCEPROP 1 LAST VALUE 4.7K
J 0
(3545 175);
DISPLAY 0.638298 (3545 175);
FORCEPROP 1 LAST TOLERANCE 5%
J 0
(3545 125);
DISPLAY 0.638298 (3545 125);
FORCEPROP 1 LAST MATERIAL CHIP
J 0
(3540 25);
DISPLAY 0.638298 (3540 25);
FORCEPROP 1 LAST $LOCATION R4560
J 0
(3545 225);
DISPLAY 0.638298 (3545 225);
FORCEPROP 1 LASTPIN (3500 200) $PN 1
J 0
(3505 162);
DISPLAY 0.787234 (3505 162);
FORCEPROP 1 LASTPIN (3500 0) $PN 2
J 0
(3505 10);
DISPLAY 0.787234 (3505 10);
FORCEPROP 2 LAST CDS_LIB pure_quanta
J 0
(3500 100);
PAINT MONO (3500 100);
DISPLAY INVISIBLE (3500 100);
FORCEPROP 1 LAST PATH I124
J 0
(3550 275);
DISPLAY 0.978723 (3550 275);
PAINT WHITE (3550 275);
DISPLAY INVISIBLE (3550 275);
FORCEPROP 2 LAST CDS_LOCATION R4560
J 0
(3550 325);
DISPLAY 1.021277 (3550 325);
DISPLAY INVISIBLE (3550 325);
FORCEPROP 2 LAST $SEC 1
J 0
(3550 325);
DISPLAY 0.680851 (3550 325);
PAINT MONO (3550 325);
DISPLAY INVISIBLE (3550 325);
FORCEPROP 2 LAST CDS_SEC 1
J 0
(3550 325);
DISPLAY 1.021277 (3550 325);
DISPLAY INVISIBLE (3550 325);
FORCEADD UNIVERSAL_GND..1
(3500 -875);
FORCEPROP 3 LASTPIN (3500 -825) SIG_NAME GND\g
J 0
(3510 -815);
DISPLAY 0.659574 (3510 -815);
PAINT MONO (3510 -815);
DISPLAY INVISIBLE (3510 -815);
FORCEPROP 1 LAST HDL_POWER GND
J 1
(3525 -950);
DISPLAY 0.872340 (3525 -950);
PAINT GREEN (3525 -950);
DISPLAY INVISIBLE (3525 -950);
FORCEPROP 2 LAST CDS_LIB logical_power
J 0
(3500 -875);
DISPLAY INVISIBLE (3500 -875);
FORCEPROP 1 LAST PATH I125
J 0
(3575 -875);
DISPLAY 0.872340 (3575 -875);
PAINT AQUA (3575 -875);
DISPLAY INVISIBLE (3575 -875);
FORCEADD MOSFET_NCH_DUAL..1
(3450 -500);
FORCEPROP 1 LAST PART_NUMBER BAM138K0003
J 0
(3601 -586);
DISPLAY 0.723404 (3601 -586);
PAINT GREEN (3601 -586);
DISPLAY INVISIBLE (3601 -586);
FORCEPROP 2 LAST VALUE PJT138K
J 0
(3625 -475);
DISPLAY 1.021277 (3625 -475);
FORCEPROP 1 LAST MATERIAL IC
J 0
(3601 -651);
DISPLAY 0.723404 (3601 -651);
PAINT GREEN (3601 -651);
FORCEPROP 2 LAST PART_TYPE SMLF
J 0
(3625 -425);
DISPLAY 1.021277 (3625 -425);
FORCEPROP 1 LAST $LOCATION Q146
J 0
(3601 -526);
DISPLAY 0.723404 (3601 -526);
PAINT GREEN (3601 -526);
FORCEPROP 0 LASTPIN (3500 -300) $PN 6
R 1
J 0
(3490 -290);
DISPLAY 0.680851 (3490 -290);
PAINT MONO (3490 -290);
FORCEPROP 0 LASTPIN (3250 -550) $PN 2
J 2
(3240 -540);
DISPLAY 0.680851 (3240 -540);
PAINT MONO (3240 -540);
FORCEPROP 0 LASTPIN (3500 -700) $PN 1
R 1
J 2
(3490 -710);
DISPLAY 0.680851 (3490 -710);
PAINT MONO (3490 -710);
FORCEPROP 1 LAST CDS_LMAN_SYM_OUTLINE -150,150,150,-150
J 0
(3450 -500);
DISPLAY 0.468085 (3450 -500);
PAINT GREEN (3450 -500);
DISPLAY INVISIBLE (3450 -500);
FORCEPROP 1 LAST NEEDS_NO_SIZE TRUE
J 0
(3450 -501);
DISPLAY 0.468085 (3450 -501);
PAINT GREEN (3450 -501);
DISPLAY INVISIBLE (3450 -501);
FORCEPROP 2 LAST CDS_LIB pure_quanta
J 0
(3450 -500);
DISPLAY INVISIBLE (3450 -500);
FORCEPROP 1 LAST PATH I126
J 0
(3450 -500);
DISPLAY 0.723404 (3450 -500);
PAINT GREEN (3450 -500);
DISPLAY INVISIBLE (3450 -500);
FORCEPROP 0 LAST CDS_LOCATION Q146
J 0
(3625 -375);
DISPLAY 1.021277 (3625 -375);
DISPLAY INVISIBLE (3625 -375);
FORCEPROP 0 LAST $SEC 1
J 0
(3625 -375);
DISPLAY 0.680851 (3625 -375);
PAINT MONO (3625 -375);
DISPLAY INVISIBLE (3625 -375);
FORCEPROP 2 LAST CDS_SEC 1
J 0
(3625 -375);
DISPLAY 1.021277 (3625 -375);
DISPLAY INVISIBLE (3625 -375);
FORCEADD UNIVERSAL_POWER..1
(2325 -25);
FORCEPROP 3 LASTPIN (2325 -75) SIG_NAME P3V3_AUX\g
J 0
(2335 -65);
DISPLAY 0.659574 (2335 -65);
PAINT MONO (2335 -65);
DISPLAY INVISIBLE (2335 -65);
FORCEPROP 1 LAST HDL_POWER P3V3_AUX
J 1
(2325 25);
DISPLAY 0.872340 (2325 25);
PAINT GREEN (2325 25);
FORCEPROP 2 LAST CDS_LIB logical_power
J 0
(2325 -25);
PAINT MONO (2325 -25);
DISPLAY INVISIBLE (2325 -25);
FORCEPROP 1 LAST PATH I127
J 0
(2375 0);
DISPLAY 0.872340 (2375 0);
PAINT AQUA (2375 0);
DISPLAY INVISIBLE (2375 0);
FORCEADD Q_RES..2
(2350 -750);
FORCEPROP 1 LAST PART_NUMBER CS41002FB09
J 0
(2390 -875);
DISPLAY 0.510638 (2390 -875);
DISPLAY INVISIBLE (2390 -875);
FORCEPROP 1 LAST VALUE 100K
J 0
(2395 -675);
DISPLAY 0.510638 (2395 -675);
FORCEPROP 1 LAST PACK_TYPE 0402LF
J 0
(2390 -925);
DISPLAY 0.510638 (2390 -925);
FORCEPROP 1 LAST WATTAGE 1/16W
J 0
(2390 -775);
DISPLAY 0.510638 (2390 -775);
FORCEPROP 1 LAST TOLERANCE 1%
J 0
(2395 -725);
DISPLAY 0.510638 (2395 -725);
FORCEPROP 1 LAST MATERIAL CHIP
J 0
(2390 -825);
DISPLAY 0.510638 (2390 -825);
FORCEPROP 1 LAST $LOCATION R4559
J 0
(2395 -625);
DISPLAY 0.978723 (2395 -625);
FORCEPROP 1 LASTPIN (2350 -650) $PN 1
J 0
(2355 -688);
DISPLAY 0.787234 (2355 -688);
PAINT MONO (2355 -688);
FORCEPROP 1 LASTPIN (2350 -850) $PN 2
J 0
(2355 -840);
DISPLAY 0.787234 (2355 -840);
PAINT MONO (2355 -840);
FORCEPROP 1 LAST PATH I129
J 0
(2400 -575);
DISPLAY 0.978723 (2400 -575);
PAINT WHITE (2400 -575);
DISPLAY INVISIBLE (2400 -575);
FORCEPROP 2 LAST CDS_LIB pure_quanta
J 0
(2350 -750);
DISPLAY INVISIBLE (2350 -750);
FORCEPROP 0 LAST CDS_LOCATION R4559
J 0
(2400 -575);
DISPLAY 1.021277 (2400 -575);
DISPLAY INVISIBLE (2400 -575);
FORCEPROP 0 LAST $SEC 1
J 0
(2400 -575);
DISPLAY 0.680851 (2400 -575);
PAINT MONO (2400 -575);
DISPLAY INVISIBLE (2400 -575);
FORCEPROP 0 LAST CDS_SEC 1
J 0
(2400 -575);
DISPLAY 1.021277 (2400 -575);
DISPLAY INVISIBLE (2400 -575);
FORCEADD Q_RES..2
(-2300 3725);
FORCEPROP 1 LAST PART_NUMBER CS35492FB03
J 0
(-2260 3600);
DISPLAY 0.787234 (-2260 3600);
DISPLAY INVISIBLE (-2260 3600);
FORCEPROP 1 LAST VALUE 54.9K
J 0
(-2255 3800);
DISPLAY 0.787234 (-2255 3800);
FORCEPROP 1 LAST TOLERANCE 1%
J 0
(-2255 3750);
DISPLAY 0.787234 (-2255 3750);
FORCEPROP 1 LAST WATTAGE 1/16W
J 0
(-2260 3700);
DISPLAY 0.787234 (-2260 3700);
FORCEPROP 1 LAST PACK_TYPE 0402LF
J 0
(-2260 3550);
DISPLAY 0.787234 (-2260 3550);
FORCEPROP 1 LAST MATERIAL EMPTY
J 0
(-2260 3650);
DISPLAY 0.787234 (-2260 3650);
PAINT RED (-2260 3650);
FORCEPROP 1 LAST $LOCATION R4119
J 0
(-2255 3850);
DISPLAY 0.978723 (-2255 3850);
FORCEPROP 1 LASTPIN (-2300 3825) $PN 1
J 0
(-2295 3787);
DISPLAY 0.787234 (-2295 3787);
PAINT MONO (-2295 3787);
FORCEPROP 1 LASTPIN (-2300 3625) $PN 2
J 0
(-2295 3635);
DISPLAY 0.787234 (-2295 3635);
PAINT MONO (-2295 3635);
FORCEPROP 1 LAST PATH I13
J 0
(-2250 3900);
DISPLAY 0.978723 (-2250 3900);
PAINT WHITE (-2250 3900);
DISPLAY INVISIBLE (-2250 3900);
FORCEPROP 2 LAST CDS_LIB pure_quanta
J 0
(-2300 3725);
DISPLAY INVISIBLE (-2300 3725);
FORCEPROP 0 LAST CDS_LOCATION R4119
J 0
(-2250 3900);
DISPLAY 1.021277 (-2250 3900);
DISPLAY INVISIBLE (-2250 3900);
FORCEPROP 0 LAST $SEC 1
J 0
(-2250 3900);
DISPLAY 0.680851 (-2250 3900);
PAINT MONO (-2250 3900);
DISPLAY INVISIBLE (-2250 3900);
FORCEPROP 0 LAST CDS_SEC 1
J 0
(-2250 3900);
DISPLAY 1.021277 (-2250 3900);
DISPLAY INVISIBLE (-2250 3900);
FORCEADD UNIVERSAL_GND..1
(2350 -1025);
FORCEPROP 3 LASTPIN (2350 -975) SIG_NAME GND\g
J 0
(2360 -965);
DISPLAY 0.659574 (2360 -965);
PAINT MONO (2360 -965);
DISPLAY INVISIBLE (2360 -965);
FORCEPROP 1 LAST HDL_POWER GND
J 1
(2375 -1100);
DISPLAY 0.872340 (2375 -1100);
PAINT GREEN (2375 -1100);
DISPLAY INVISIBLE (2375 -1100);
FORCEPROP 2 LAST CDS_LIB logical_power
J 0
(2350 -1025);
DISPLAY INVISIBLE (2350 -1025);
FORCEPROP 1 LAST PATH I130
J 0
(2425 -1025);
DISPLAY 0.872340 (2425 -1025);
PAINT AQUA (2425 -1025);
DISPLAY INVISIBLE (2425 -1025);
FORCEADD OFFPAGE..4
R 2
(2075 -550);
FORCEPROP 2 LAST $XR0 138 
J 0
(1793 -550);
DISPLAY 0.638298 (1793 -550);
PAINT MONO (1793 -550);
FORCEPROP 2 LAST CDS_LIB standard
J 0
(2075 -550);
DISPLAY INVISIBLE (2075 -550);
FORCEPROP 1 LAST COMMENT_BODY TRUE
J 2
(2100 -650);
DISPLAY 0.872340 (2100 -650);
PAINT GREEN (2100 -650);
DISPLAY INVISIBLE (2100 -650);
FORCEPROP 1 LAST OFFPAGE TRUE
J 2
(1750 -675);
DISPLAY 0.872340 (1750 -675);
PAINT GREEN (1750 -675);
DISPLAY INVISIBLE (1750 -675);
FORCEPROP 2 LAST PATH I131
J 0
(1800 -500);
DISPLAY 1.021277 (1800 -500);
DISPLAY INVISIBLE (1800 -500);
FORCEADD Q_RES..2
(2325 -275);
FORCEPROP 1 LAST PART_NUMBER CS41002FB09
J 0
(2365 -400);
DISPLAY 0.510638 (2365 -400);
DISPLAY INVISIBLE (2365 -400);
FORCEPROP 1 LAST PACK_TYPE 0402LF
J 0
(2365 -450);
DISPLAY 0.510638 (2365 -450);
FORCEPROP 1 LAST VALUE 100K
J 0
(2370 -200);
DISPLAY 0.510638 (2370 -200);
FORCEPROP 1 LAST WATTAGE 1/16W
J 0
(2365 -300);
DISPLAY 0.510638 (2365 -300);
FORCEPROP 1 LAST MATERIAL EMPTY
J 0
(2365 -350);
DISPLAY 0.510638 (2365 -350);
PAINT RED (2365 -350);
FORCEPROP 1 LAST TOLERANCE 1%
J 0
(2370 -250);
DISPLAY 0.510638 (2370 -250);
FORCEPROP 1 LAST $LOCATION R4562
J 0
(2370 -150);
DISPLAY 0.978723 (2370 -150);
FORCEPROP 1 LASTPIN (2325 -175) $PN 1
J 0
(2330 -213);
DISPLAY 0.787234 (2330 -213);
PAINT MONO (2330 -213);
FORCEPROP 1 LASTPIN (2325 -375) $PN 2
J 0
(2330 -365);
DISPLAY 0.787234 (2330 -365);
PAINT MONO (2330 -365);
FORCEPROP 1 LAST PATH I132
J 0
(2375 -100);
DISPLAY 0.978723 (2375 -100);
PAINT WHITE (2375 -100);
DISPLAY INVISIBLE (2375 -100);
FORCEPROP 2 LAST CDS_LIB pure_quanta
J 0
(2325 -275);
DISPLAY INVISIBLE (2325 -275);
FORCEPROP 0 LAST CDS_LOCATION R4562
J 0
(2375 -100);
DISPLAY 1.021277 (2375 -100);
DISPLAY INVISIBLE (2375 -100);
FORCEPROP 0 LAST $SEC 1
J 0
(2375 -100);
DISPLAY 0.680851 (2375 -100);
PAINT MONO (2375 -100);
DISPLAY INVISIBLE (2375 -100);
FORCEPROP 0 LAST CDS_SEC 1
J 0
(2375 -100);
DISPLAY 1.021277 (2375 -100);
DISPLAY INVISIBLE (2375 -100);
FORCEADD Q_RES..1
(-775 175);
FORCEPROP 1 LAST PART_NUMBER CS00002JB13
J 0
(-825 225);
DISPLAY 0.510638 (-825 225);
DISPLAY INVISIBLE (-825 225);
FORCEPROP 1 LAST WATTAGE 1/16W
J 2
(-525 275);
DISPLAY 0.510638 (-525 275);
FORCEPROP 1 LAST PACK_TYPE 0402LF
J 0
(-875 275);
DISPLAY 0.510638 (-875 275);
FORCEPROP 1 LAST VALUE 0
J 2
(-650 175);
DISPLAY 0.510638 (-650 175);
FORCEPROP 1 LAST TOLERANCE 5%
J 0
(-625 175);
DISPLAY 0.510638 (-625 175);
FORCEPROP 1 LAST MATERIAL EMPTY
J 0
(-550 175);
DISPLAY 0.510638 (-550 175);
PAINT RED (-550 175);
FORCEPROP 1 LAST $LOCATION R4574
J 0
(-1025 175);
DISPLAY 0.787234 (-1025 175);
FORCEPROP 1 LASTPIN (-875 175) $PN 1
J 0
(-863 187);
DISPLAY 0.787234 (-863 187);
PAINT MONO (-863 187);
FORCEPROP 1 LASTPIN (-675 175) $PN 2
J 0
(-713 187);
DISPLAY 0.787234 (-713 187);
PAINT MONO (-713 187);
FORCEPROP 2 LAST CDS_LIB pure_quanta
J 0
(-775 175);
DISPLAY INVISIBLE (-775 175);
FORCEPROP 1 LAST PATH I136
J 0
(-825 325);
DISPLAY 0.978723 (-825 325);
PAINT WHITE (-825 325);
DISPLAY INVISIBLE (-825 325);
FORCEPROP 0 LAST CDS_LOCATION R4574
J 0
(-525 300);
DISPLAY 1.021277 (-525 300);
DISPLAY INVISIBLE (-525 300);
FORCEPROP 0 LAST $SEC 1
J 0
(-525 300);
DISPLAY 0.680851 (-525 300);
PAINT MONO (-525 300);
DISPLAY INVISIBLE (-525 300);
FORCEPROP 0 LAST CDS_SEC 1
J 0
(-525 300);
DISPLAY 1.021277 (-525 300);
DISPLAY INVISIBLE (-525 300);
FORCEADD Q_RES..1
(3800 4775);
FORCEPROP 1 LAST PART_NUMBER CS00002JB13
J 0
(3750 4825);
DISPLAY 0.510638 (3750 4825);
DISPLAY INVISIBLE (3750 4825);
FORCEPROP 1 LAST VALUE 0
J 2
(3925 4775);
DISPLAY 0.510638 (3925 4775);
FORCEPROP 1 LAST WATTAGE 1/16W
J 2
(4050 4875);
DISPLAY 0.510638 (4050 4875);
FORCEPROP 1 LAST PACK_TYPE 0402LF
J 0
(3700 4875);
DISPLAY 0.510638 (3700 4875);
FORCEPROP 1 LAST TOLERANCE 5%
J 0
(3950 4775);
DISPLAY 0.510638 (3950 4775);
FORCEPROP 1 LAST MATERIAL EMPTY
J 0
(4025 4775);
DISPLAY 0.510638 (4025 4775);
PAINT RED (4025 4775);
FORCEPROP 1 LAST $LOCATION R4577
J 0
(3550 4775);
DISPLAY 0.787234 (3550 4775);
FORCEPROP 1 LASTPIN (3700 4775) $PN 1
J 0
(3712 4787);
DISPLAY 0.787234 (3712 4787);
PAINT MONO (3712 4787);
FORCEPROP 1 LASTPIN (3900 4775) $PN 2
J 0
(3862 4787);
DISPLAY 0.787234 (3862 4787);
PAINT MONO (3862 4787);
FORCEPROP 1 LAST PATH I137
J 0
(3750 4925);
DISPLAY 0.978723 (3750 4925);
PAINT WHITE (3750 4925);
DISPLAY INVISIBLE (3750 4925);
FORCEPROP 2 LAST CDS_LIB pure_quanta
J 0
(3800 4775);
DISPLAY INVISIBLE (3800 4775);
FORCEPROP 0 LAST CDS_LOCATION R4577
J 0
(4050 4900);
DISPLAY 1.021277 (4050 4900);
DISPLAY INVISIBLE (4050 4900);
FORCEPROP 0 LAST $SEC 1
J 0
(4050 4900);
DISPLAY 0.680851 (4050 4900);
PAINT MONO (4050 4900);
DISPLAY INVISIBLE (4050 4900);
FORCEPROP 0 LAST CDS_SEC 1
J 0
(4050 4900);
DISPLAY 1.021277 (4050 4900);
DISPLAY INVISIBLE (4050 4900);
FORCEADD Q_RES..1
(3850 3400);
FORCEPROP 1 LAST PART_NUMBER CS00002JB13
J 0
(3800 3450);
DISPLAY 0.510638 (3800 3450);
DISPLAY INVISIBLE (3800 3450);
FORCEPROP 1 LAST MATERIAL EMPTY
J 0
(4075 3400);
DISPLAY 0.510638 (4075 3400);
PAINT RED (4075 3400);
FORCEPROP 1 LAST VALUE 0
J 2
(3975 3400);
DISPLAY 0.510638 (3975 3400);
FORCEPROP 1 LAST TOLERANCE 5%
J 0
(4000 3400);
DISPLAY 0.510638 (4000 3400);
FORCEPROP 1 LAST PACK_TYPE 0402LF
J 0
(3750 3500);
DISPLAY 0.510638 (3750 3500);
FORCEPROP 1 LAST WATTAGE 1/16W
J 2
(4100 3500);
DISPLAY 0.510638 (4100 3500);
FORCEPROP 1 LAST $LOCATION R4578
J 0
(3600 3400);
DISPLAY 0.787234 (3600 3400);
FORCEPROP 1 LASTPIN (3750 3400) $PN 1
J 0
(3762 3412);
DISPLAY 0.787234 (3762 3412);
PAINT MONO (3762 3412);
FORCEPROP 1 LASTPIN (3950 3400) $PN 2
J 0
(3912 3412);
DISPLAY 0.787234 (3912 3412);
PAINT MONO (3912 3412);
FORCEPROP 1 LAST PATH I138
J 0
(3800 3550);
DISPLAY 0.978723 (3800 3550);
PAINT WHITE (3800 3550);
DISPLAY INVISIBLE (3800 3550);
FORCEPROP 2 LAST CDS_LIB pure_quanta
J 0
(3850 3400);
DISPLAY INVISIBLE (3850 3400);
FORCEPROP 0 LAST CDS_LOCATION R4578
J 0
(4100 3525);
DISPLAY 1.021277 (4100 3525);
DISPLAY INVISIBLE (4100 3525);
FORCEPROP 0 LAST $SEC 1
J 0
(4100 3525);
DISPLAY 0.680851 (4100 3525);
PAINT MONO (4100 3525);
DISPLAY INVISIBLE (4100 3525);
FORCEPROP 0 LAST CDS_SEC 1
J 0
(4100 3525);
DISPLAY 1.021277 (4100 3525);
DISPLAY INVISIBLE (4100 3525);
FORCEADD Q_RES..1
(3775 1950);
FORCEPROP 1 LAST PART_NUMBER CS00002JB13
J 0
(3725 2000);
DISPLAY 0.510638 (3725 2000);
DISPLAY INVISIBLE (3725 2000);
FORCEPROP 1 LAST TOLERANCE 5%
J 0
(3925 1950);
DISPLAY 0.510638 (3925 1950);
FORCEPROP 1 LAST WATTAGE 1/16W
J 2
(4025 2050);
DISPLAY 0.510638 (4025 2050);
FORCEPROP 1 LAST PACK_TYPE 0402LF
J 0
(3675 2050);
DISPLAY 0.510638 (3675 2050);
FORCEPROP 1 LAST MATERIAL EMPTY
J 0
(4000 1950);
DISPLAY 0.510638 (4000 1950);
PAINT RED (4000 1950);
FORCEPROP 1 LAST VALUE 0
J 2
(3900 1950);
DISPLAY 0.510638 (3900 1950);
FORCEPROP 1 LAST $LOCATION R4576
J 0
(3550 1950);
DISPLAY 0.787234 (3550 1950);
FORCEPROP 1 LASTPIN (3675 1950) $PN 1
J 0
(3687 1962);
DISPLAY 0.787234 (3687 1962);
PAINT MONO (3687 1962);
FORCEPROP 1 LASTPIN (3875 1950) $PN 2
J 0
(3837 1962);
DISPLAY 0.787234 (3837 1962);
PAINT MONO (3837 1962);
FORCEPROP 2 LAST CDS_LIB pure_quanta
J 0
(3775 1950);
DISPLAY INVISIBLE (3775 1950);
FORCEPROP 1 LAST PATH I139
J 0
(3725 2100);
DISPLAY 0.978723 (3725 2100);
PAINT WHITE (3725 2100);
DISPLAY INVISIBLE (3725 2100);
FORCEPROP 0 LAST CDS_LOCATION R4576
J 0
(4025 2075);
DISPLAY 1.021277 (4025 2075);
DISPLAY INVISIBLE (4025 2075);
FORCEPROP 0 LAST $SEC 1
J 0
(4025 2075);
DISPLAY 0.680851 (4025 2075);
PAINT MONO (4025 2075);
DISPLAY INVISIBLE (4025 2075);
FORCEPROP 0 LAST CDS_SEC 1
J 0
(4025 2075);
DISPLAY 1.021277 (4025 2075);
DISPLAY INVISIBLE (4025 2075);
FORCEADD Q_RES..2
(-2275 3250);
FORCEPROP 1 LAST PART_NUMBER CS41002FB09
J 0
(-2235 3125);
DISPLAY 0.510638 (-2235 3125);
DISPLAY INVISIBLE (-2235 3125);
FORCEPROP 1 LAST MATERIAL EMPTY
J 0
(-2235 3175);
DISPLAY 0.510638 (-2235 3175);
PAINT RED (-2235 3175);
FORCEPROP 1 LAST WATTAGE 1/16W
J 0
(-2235 3225);
DISPLAY 0.510638 (-2235 3225);
FORCEPROP 1 LAST TOLERANCE 1%
J 0
(-2230 3275);
DISPLAY 0.510638 (-2230 3275);
FORCEPROP 1 LAST VALUE 100K
J 0
(-2230 3325);
DISPLAY 0.510638 (-2230 3325);
FORCEPROP 1 LAST PACK_TYPE 0402LF
J 0
(-2235 3075);
DISPLAY 0.510638 (-2235 3075);
FORCEPROP 1 LAST $LOCATION R4120
J 0
(-2230 3375);
DISPLAY 0.978723 (-2230 3375);
FORCEPROP 1 LASTPIN (-2275 3350) $PN 1
J 0
(-2270 3312);
DISPLAY 0.787234 (-2270 3312);
PAINT MONO (-2270 3312);
FORCEPROP 1 LASTPIN (-2275 3150) $PN 2
J 0
(-2270 3160);
DISPLAY 0.787234 (-2270 3160);
PAINT MONO (-2270 3160);
FORCEPROP 2 LAST CDS_LIB pure_quanta
J 0
(-2275 3250);
DISPLAY INVISIBLE (-2275 3250);
FORCEPROP 1 LAST PATH I14
J 0
(-2225 3425);
DISPLAY 0.978723 (-2225 3425);
PAINT WHITE (-2225 3425);
DISPLAY INVISIBLE (-2225 3425);
FORCEPROP 0 LAST CDS_LOCATION R4120
J 0
(-2225 3425);
DISPLAY 1.021277 (-2225 3425);
DISPLAY INVISIBLE (-2225 3425);
FORCEPROP 0 LAST $SEC 1
J 0
(-2225 3425);
DISPLAY 0.680851 (-2225 3425);
PAINT MONO (-2225 3425);
DISPLAY INVISIBLE (-2225 3425);
FORCEPROP 0 LAST CDS_SEC 1
J 0
(-2225 3425);
DISPLAY 1.021277 (-2225 3425);
DISPLAY INVISIBLE (-2225 3425);
FORCEADD Q_RES..1
(-850 1650);
FORCEPROP 1 LAST PART_NUMBER CS00002JB13
J 0
(-900 1700);
DISPLAY 0.510638 (-900 1700);
DISPLAY INVISIBLE (-900 1700);
FORCEPROP 1 LAST WATTAGE 1/16W
J 2
(-600 1750);
DISPLAY 0.510638 (-600 1750);
FORCEPROP 1 LAST PACK_TYPE 0402LF
J 0
(-950 1750);
DISPLAY 0.510638 (-950 1750);
FORCEPROP 1 LAST VALUE 0
J 2
(-725 1650);
DISPLAY 0.510638 (-725 1650);
FORCEPROP 1 LAST MATERIAL EMPTY
J 0
(-625 1650);
DISPLAY 0.510638 (-625 1650);
PAINT RED (-625 1650);
FORCEPROP 1 LAST TOLERANCE 5%
J 0
(-700 1650);
DISPLAY 0.510638 (-700 1650);
FORCEPROP 1 LAST $LOCATION R4573
J 0
(-1100 1650);
DISPLAY 0.787234 (-1100 1650);
FORCEPROP 1 LASTPIN (-950 1650) $PN 1
J 0
(-938 1662);
DISPLAY 0.787234 (-938 1662);
PAINT MONO (-938 1662);
FORCEPROP 1 LASTPIN (-750 1650) $PN 2
J 0
(-788 1662);
DISPLAY 0.787234 (-788 1662);
PAINT MONO (-788 1662);
FORCEPROP 1 LAST PATH I140
J 0
(-900 1800);
DISPLAY 0.978723 (-900 1800);
PAINT WHITE (-900 1800);
DISPLAY INVISIBLE (-900 1800);
FORCEPROP 2 LAST CDS_LIB pure_quanta
J 0
(-850 1650);
DISPLAY INVISIBLE (-850 1650);
FORCEPROP 0 LAST CDS_LOCATION R4573
J 0
(-600 1775);
DISPLAY 1.021277 (-600 1775);
DISPLAY INVISIBLE (-600 1775);
FORCEPROP 0 LAST $SEC 1
J 0
(-600 1775);
DISPLAY 0.680851 (-600 1775);
PAINT MONO (-600 1775);
DISPLAY INVISIBLE (-600 1775);
FORCEPROP 0 LAST CDS_SEC 1
J 0
(-600 1775);
DISPLAY 1.021277 (-600 1775);
DISPLAY INVISIBLE (-600 1775);
FORCEADD Q_RES..1
(-850 3100);
FORCEPROP 1 LAST PART_NUMBER CS00002JB13
J 0
(-900 3150);
DISPLAY 0.510638 (-900 3150);
DISPLAY INVISIBLE (-900 3150);
FORCEPROP 1 LAST TOLERANCE 5%
J 0
(-700 3100);
DISPLAY 0.510638 (-700 3100);
FORCEPROP 1 LAST VALUE 0
J 2
(-725 3100);
DISPLAY 0.510638 (-725 3100);
FORCEPROP 1 LAST WATTAGE 1/16W
J 2
(-600 3200);
DISPLAY 0.510638 (-600 3200);
FORCEPROP 1 LAST MATERIAL EMPTY
J 0
(-625 3100);
DISPLAY 0.510638 (-625 3100);
PAINT RED (-625 3100);
FORCEPROP 1 LAST PACK_TYPE 0402LF
J 0
(-950 3200);
DISPLAY 0.510638 (-950 3200);
FORCEPROP 1 LAST $LOCATION R4572
J 0
(-1100 3100);
DISPLAY 0.787234 (-1100 3100);
FORCEPROP 1 LASTPIN (-950 3100) $PN 1
J 0
(-938 3112);
DISPLAY 0.787234 (-938 3112);
PAINT MONO (-938 3112);
FORCEPROP 1 LASTPIN (-750 3100) $PN 2
J 0
(-788 3112);
DISPLAY 0.787234 (-788 3112);
PAINT MONO (-788 3112);
FORCEPROP 1 LAST PATH I141
J 0
(-900 3250);
DISPLAY 0.978723 (-900 3250);
PAINT WHITE (-900 3250);
DISPLAY INVISIBLE (-900 3250);
FORCEPROP 2 LAST CDS_LIB pure_quanta
J 0
(-850 3100);
DISPLAY INVISIBLE (-850 3100);
FORCEPROP 0 LAST CDS_LOCATION R4572
J 0
(-600 3225);
DISPLAY 1.021277 (-600 3225);
DISPLAY INVISIBLE (-600 3225);
FORCEPROP 0 LAST $SEC 1
J 0
(-600 3225);
DISPLAY 0.680851 (-600 3225);
PAINT MONO (-600 3225);
DISPLAY INVISIBLE (-600 3225);
FORCEPROP 0 LAST CDS_SEC 1
J 0
(-600 3225);
DISPLAY 1.021277 (-600 3225);
DISPLAY INVISIBLE (-600 3225);
FORCEADD Q_RES..1
(-725 4550);
FORCEPROP 1 LAST PART_NUMBER CS00002JB13
J 0
(-775 4600);
DISPLAY 0.510638 (-775 4600);
DISPLAY INVISIBLE (-775 4600);
FORCEPROP 1 LAST PACK_TYPE 0402LF
J 0
(-825 4650);
DISPLAY 0.510638 (-825 4650);
FORCEPROP 1 LAST VALUE 0
J 2
(-600 4550);
DISPLAY 0.510638 (-600 4550);
FORCEPROP 1 LAST MATERIAL EMPTY
J 0
(-500 4550);
DISPLAY 0.510638 (-500 4550);
PAINT RED (-500 4550);
FORCEPROP 1 LAST TOLERANCE 5%
J 0
(-575 4550);
DISPLAY 0.510638 (-575 4550);
FORCEPROP 1 LAST WATTAGE 1/16W
J 2
(-475 4650);
DISPLAY 0.510638 (-475 4650);
FORCEPROP 1 LAST $LOCATION R4575
J 0
(-1000 4550);
DISPLAY 0.787234 (-1000 4550);
FORCEPROP 1 LASTPIN (-825 4550) $PN 1
J 0
(-813 4562);
DISPLAY 0.787234 (-813 4562);
PAINT MONO (-813 4562);
FORCEPROP 1 LASTPIN (-625 4550) $PN 2
J 0
(-663 4562);
DISPLAY 0.787234 (-663 4562);
PAINT MONO (-663 4562);
FORCEPROP 1 LAST PATH I142
J 0
(-775 4700);
DISPLAY 0.978723 (-775 4700);
PAINT WHITE (-775 4700);
DISPLAY INVISIBLE (-775 4700);
FORCEPROP 2 LAST CDS_LIB pure_quanta
J 0
(-725 4550);
DISPLAY INVISIBLE (-725 4550);
FORCEPROP 0 LAST CDS_LOCATION R4575
J 0
(-475 4675);
DISPLAY 1.021277 (-475 4675);
DISPLAY INVISIBLE (-475 4675);
FORCEPROP 0 LAST $SEC 1
J 0
(-475 4675);
DISPLAY 0.680851 (-475 4675);
PAINT MONO (-475 4675);
DISPLAY INVISIBLE (-475 4675);
FORCEPROP 0 LAST CDS_SEC 1
J 0
(-475 4675);
DISPLAY 1.021277 (-475 4675);
DISPLAY INVISIBLE (-475 4675);
FORCEADD Q_RES..2
(-2300 900);
FORCEPROP 1 LAST PART_NUMBER CS31002FB08
J 0
(-2260 775);
DISPLAY 0.510638 (-2260 775);
DISPLAY INVISIBLE (-2260 775);
FORCEPROP 1 LAST VALUE 10K
J 0
(-2255 975);
DISPLAY 0.510638 (-2255 975);
FORCEPROP 1 LAST PACK_TYPE 0402LF
J 0
(-2260 725);
DISPLAY 0.510638 (-2260 725);
FORCEPROP 1 LAST MATERIAL CHIP
J 0
(-2260 825);
DISPLAY 0.510638 (-2260 825);
FORCEPROP 1 LAST TOLERANCE 1%
J 0
(-2255 925);
DISPLAY 0.510638 (-2255 925);
FORCEPROP 1 LAST WATTAGE 1/16W
J 0
(-2260 875);
DISPLAY 0.510638 (-2260 875);
FORCEPROP 1 LAST LOCATION R4121
J 0
(-2255 1025);
DISPLAY 0.978723 (-2255 1025);
FORCEPROP 1 LASTPIN (-2300 1000) $PN 1
J 0
(-2295 962);
DISPLAY 0.787234 (-2295 962);
PAINT MONO (-2295 962);
FORCEPROP 1 LASTPIN (-2300 800) $PN 2
J 0
(-2295 810);
DISPLAY 0.787234 (-2295 810);
PAINT MONO (-2295 810);
FORCEPROP 1 LAST PATH I143
J 0
(-2250 1075);
DISPLAY 0.978723 (-2250 1075);
PAINT WHITE (-2250 1075);
DISPLAY INVISIBLE (-2250 1075);
FORCEPROP 2 LAST CDS_LIB pure_quanta
J 0
(-2300 900);
DISPLAY INVISIBLE (-2300 900);
FORCEPROP 0 LAST $SEC 1
J 0
(-2250 1075);
DISPLAY 0.680851 (-2250 1075);
PAINT MONO (-2250 1075);
DISPLAY INVISIBLE (-2250 1075);
FORCEPROP 0 LAST CDS_SEC 1
J 0
(-2250 1075);
DISPLAY 1.021277 (-2250 1075);
DISPLAY INVISIBLE (-2250 1075);
FORCEADD Q_RES..2
(2350 2650);
FORCEPROP 1 LAST PART_NUMBER CS31002FB08
J 0
(2390 2525);
DISPLAY 0.510638 (2390 2525);
DISPLAY INVISIBLE (2390 2525);
FORCEPROP 1 LAST TOLERANCE 1%
J 0
(2395 2675);
DISPLAY 0.510638 (2395 2675);
FORCEPROP 1 LAST MATERIAL CHIP
J 0
(2390 2575);
DISPLAY 0.510638 (2390 2575);
FORCEPROP 1 LAST PACK_TYPE 0402LF
J 0
(2390 2475);
DISPLAY 0.510638 (2390 2475);
FORCEPROP 1 LAST WATTAGE 1/16W
J 0
(2390 2625);
DISPLAY 0.510638 (2390 2625);
FORCEPROP 1 LAST VALUE 10K
J 0
(2395 2725);
DISPLAY 0.510638 (2395 2725);
FORCEPROP 1 LAST LOCATION R4135
J 0
(2395 2775);
DISPLAY 0.978723 (2395 2775);
FORCEPROP 1 LASTPIN (2350 2750) $PN 1
J 0
(2355 2712);
DISPLAY 0.787234 (2355 2712);
PAINT MONO (2355 2712);
FORCEPROP 1 LASTPIN (2350 2550) $PN 2
J 0
(2355 2560);
DISPLAY 0.787234 (2355 2560);
PAINT MONO (2355 2560);
FORCEPROP 2 LAST CDS_LIB pure_quanta
J 0
(2350 2650);
DISPLAY INVISIBLE (2350 2650);
FORCEPROP 1 LAST PATH I144
J 0
(2400 2825);
DISPLAY 0.978723 (2400 2825);
PAINT WHITE (2400 2825);
DISPLAY INVISIBLE (2400 2825);
FORCEPROP 0 LAST $SEC 1
J 0
(2400 2825);
DISPLAY 0.680851 (2400 2825);
PAINT MONO (2400 2825);
DISPLAY INVISIBLE (2400 2825);
FORCEPROP 0 LAST CDS_SEC 1
J 0
(2400 2825);
DISPLAY 1.021277 (2400 2825);
DISPLAY INVISIBLE (2400 2825);
FORCEADD Q_RES..2
(-2225 -650);
FORCEPROP 1 LAST PART_NUMBER CS31002FB08
J 0
(-2185 -775);
DISPLAY 0.510638 (-2185 -775);
DISPLAY INVISIBLE (-2185 -775);
FORCEPROP 1 LAST VALUE 10K
J 0
(-2180 -575);
DISPLAY 0.510638 (-2180 -575);
FORCEPROP 1 LAST TOLERANCE 1%
J 0
(-2180 -625);
DISPLAY 0.510638 (-2180 -625);
FORCEPROP 1 LAST WATTAGE 1/16W
J 0
(-2185 -675);
DISPLAY 0.510638 (-2185 -675);
FORCEPROP 1 LAST PACK_TYPE 0402LF
J 0
(-2185 -825);
DISPLAY 0.510638 (-2185 -825);
FORCEPROP 1 LAST MATERIAL CHIP
J 0
(-2185 -725);
DISPLAY 0.510638 (-2185 -725);
FORCEPROP 1 LAST LOCATION R4153
J 0
(-2180 -525);
DISPLAY 0.978723 (-2180 -525);
FORCEPROP 1 LASTPIN (-2225 -550) $PN 1
J 0
(-2220 -588);
DISPLAY 0.787234 (-2220 -588);
PAINT MONO (-2220 -588);
FORCEPROP 1 LASTPIN (-2225 -750) $PN 2
J 0
(-2220 -740);
DISPLAY 0.787234 (-2220 -740);
PAINT MONO (-2220 -740);
FORCEPROP 2 LAST CDS_LIB pure_quanta
J 0
(-2225 -650);
DISPLAY INVISIBLE (-2225 -650);
FORCEPROP 1 LAST PATH I145
J 0
(-2175 -475);
DISPLAY 0.978723 (-2175 -475);
PAINT WHITE (-2175 -475);
DISPLAY INVISIBLE (-2175 -475);
FORCEPROP 0 LAST $SEC 1
J 0
(-2175 -475);
DISPLAY 0.680851 (-2175 -475);
PAINT MONO (-2175 -475);
DISPLAY INVISIBLE (-2175 -475);
FORCEPROP 0 LAST CDS_SEC 1
J 0
(-2175 -475);
DISPLAY 1.021277 (-2175 -475);
DISPLAY INVISIBLE (-2175 -475);
FORCEADD OFFPAGE..4
R 2
(-2550 3450);
FORCEPROP 2 LAST $XR0 140 
J 0
(-2832 3450);
DISPLAY 0.638298 (-2832 3450);
PAINT MONO (-2832 3450);
FORCEPROP 2 LAST PATH I15
J 0
(-2825 3500);
DISPLAY 1.021277 (-2825 3500);
DISPLAY INVISIBLE (-2825 3500);
FORCEPROP 1 LAST OFFPAGE TRUE
J 2
(-2875 3325);
DISPLAY 0.872340 (-2875 3325);
PAINT GREEN (-2875 3325);
DISPLAY INVISIBLE (-2875 3325);
FORCEPROP 1 LAST COMMENT_BODY TRUE
J 2
(-2525 3350);
DISPLAY 0.872340 (-2525 3350);
PAINT GREEN (-2525 3350);
DISPLAY INVISIBLE (-2525 3350);
FORCEPROP 2 LAST CDS_LIB standard
J 0
(-2550 3450);
DISPLAY INVISIBLE (-2550 3450);
FORCEADD UNIVERSAL_GND..1
(-2275 2975);
FORCEPROP 3 LASTPIN (-2275 3025) SIG_NAME GND\g
J 0
(-2265 3035);
DISPLAY 0.659574 (-2265 3035);
PAINT MONO (-2265 3035);
DISPLAY INVISIBLE (-2265 3035);
FORCEPROP 2 LAST CDS_LIB logical_power
J 0
(-2275 2975);
DISPLAY INVISIBLE (-2275 2975);
FORCEPROP 1 LAST HDL_POWER GND
J 1
(-2250 2900);
DISPLAY 0.872340 (-2250 2900);
PAINT GREEN (-2250 2900);
DISPLAY INVISIBLE (-2250 2900);
FORCEPROP 1 LAST PATH I16
J 0
(-2200 2975);
DISPLAY 0.872340 (-2200 2975);
PAINT AQUA (-2200 2975);
DISPLAY INVISIBLE (-2200 2975);
FORCEADD MOSFET_NCH_DUAL..2
(0 2425);
FORCEPROP 1 LAST PART_NUMBER BAM138K0003
J 0
(151 2331);
DISPLAY 0.723404 (151 2331);
PAINT GREEN (151 2331);
DISPLAY INVISIBLE (151 2331);
FORCEPROP 1 LAST MATERIAL IC
J 0
(151 2276);
DISPLAY 0.723404 (151 2276);
PAINT GREEN (151 2276);
FORCEPROP 2 LAST PART_TYPE SMLF
J 0
(175 2500);
DISPLAY 1.021277 (175 2500);
FORCEPROP 2 LAST VALUE PJT138K
J 0
(175 2450);
DISPLAY 1.021277 (175 2450);
FORCEPROP 1 LAST $LOCATION Q131
J 0
(151 2401);
DISPLAY 0.723404 (151 2401);
PAINT GREEN (151 2401);
FORCEPROP 0 LASTPIN (50 2625) $PN 3
R 1
J 0
(40 2635);
DISPLAY 0.680851 (40 2635);
PAINT MONO (40 2635);
FORCEPROP 0 LASTPIN (-200 2375) $PN 5
J 2
(-210 2385);
DISPLAY 0.680851 (-210 2385);
PAINT MONO (-210 2385);
FORCEPROP 0 LASTPIN (50 2225) $PN 4
R 1
J 2
(40 2215);
DISPLAY 0.680851 (40 2215);
PAINT MONO (40 2215);
FORCEPROP 1 LAST CDS_LMAN_SYM_OUTLINE -150,150,150,-150
J 0
(0 2425);
DISPLAY 0.468085 (0 2425);
PAINT GREEN (0 2425);
DISPLAY INVISIBLE (0 2425);
FORCEPROP 1 LAST NEEDS_NO_SIZE TRUE
J 0
(150 2316);
DISPLAY 0.468085 (150 2316);
PAINT GREEN (150 2316);
DISPLAY INVISIBLE (150 2316);
FORCEPROP 2 LAST CDS_LIB pure_quanta
J 0
(0 2425);
DISPLAY INVISIBLE (0 2425);
FORCEPROP 1 LAST PATH I19
J 0
(150 2275);
DISPLAY 0.723404 (150 2275);
PAINT GREEN (150 2275);
DISPLAY INVISIBLE (150 2275);
FORCEPROP 0 LAST CDS_LOCATION Q131
J 0
(175 2550);
DISPLAY 1.021277 (175 2550);
DISPLAY INVISIBLE (175 2550);
FORCEPROP 0 LAST $SEC 2
J 0
(175 2550);
DISPLAY 0.680851 (175 2550);
PAINT MONO (175 2550);
DISPLAY INVISIBLE (175 2550);
FORCEPROP 0 LAST CDS_SEC 2
J 0
(175 2550);
DISPLAY 1.021277 (175 2550);
DISPLAY INVISIBLE (175 2550);
FORCEADD Q_CAP..1
(800 3750);
FORCEPROP 1 LAST PART_NUMBER TMP_QCH21006JB10
J 0
(850 3600);
DISPLAY 0.638298 (850 3600);
DISPLAY INVISIBLE (850 3600);
FORCEPROP 1 LAST PACK_TYPE 0402
J 0
(850 3550);
DISPLAY 0.638298 (850 3550);
FORCEPROP 1 LAST VOLTAGE 50V
J 0
(850 3750);
DISPLAY 0.638298 (850 3750);
FORCEPROP 1 LAST MATERIAL EMPTY
J 0
(850 3650);
DISPLAY 0.638298 (850 3650);
PAINT RED (850 3650);
FORCEPROP 1 LAST TOLERANCE 5%
J 0
(850 3700);
DISPLAY 0.638298 (850 3700);
FORCEPROP 1 LAST VALUE 1000PF
J 0
(850 3800);
DISPLAY 0.638298 (850 3800);
FORCEPROP 1 LAST $LOCATION C2264
J 0
(850 3850);
DISPLAY 0.978723 (850 3850);
FORCEPROP 1 LASTPIN (800 3850) $PN 1
J 0
(810 3830);
DISPLAY 0.787234 (810 3830);
PAINT MONO (810 3830);
FORCEPROP 1 LASTPIN (800 3650) $PN 2
J 0
(810 3630);
DISPLAY 0.787234 (810 3630);
PAINT MONO (810 3630);
FORCEPROP 1 LAST PATH I2
J 0
(850 3900);
DISPLAY 0.978723 (850 3900);
PAINT WHITE (850 3900);
DISPLAY INVISIBLE (850 3900);
FORCEPROP 2 LAST CDS_LIB pure_quanta
J 0
(800 3750);
DISPLAY INVISIBLE (800 3750);
FORCEPROP 0 LAST CDS_LOCATION C2264
J 0
(850 3900);
DISPLAY 1.021277 (850 3900);
DISPLAY INVISIBLE (850 3900);
FORCEPROP 0 LAST $SEC 1
J 0
(850 3900);
DISPLAY 0.680851 (850 3900);
PAINT MONO (850 3900);
DISPLAY INVISIBLE (850 3900);
FORCEPROP 0 LAST CDS_SEC 1
J 0
(850 3900);
DISPLAY 1.021277 (850 3900);
DISPLAY INVISIBLE (850 3900);
FORCEADD UNIVERSAL_POWER..1
(50 3075);
FORCEPROP 3 LASTPIN (50 3025) SIG_NAME P3V3_AUX\g
J 0
(60 3035);
DISPLAY 0.659574 (60 3035);
PAINT MONO (60 3035);
DISPLAY INVISIBLE (60 3035);
FORCEPROP 1 LAST HDL_POWER P3V3_AUX
J 1
(50 3125);
DISPLAY 0.872340 (50 3125);
PAINT GREEN (50 3125);
FORCEPROP 1 LAST PATH I20
J 0
(100 3100);
DISPLAY 0.872340 (100 3100);
PAINT AQUA (100 3100);
DISPLAY INVISIBLE (100 3100);
FORCEPROP 2 LAST CDS_LIB logical_power
J 0
(50 3075);
PAINT MONO (50 3075);
DISPLAY INVISIBLE (50 3075);
FORCEADD Q_RES..2
(50 2850);
FORCEPROP 1 LAST PART_NUMBER CS24702JB10
J 0
(90 2675);
DISPLAY 0.638298 (90 2675);
DISPLAY INVISIBLE (90 2675);
FORCEPROP 1 LAST PACK_TYPE 0402LF
J 0
(90 2725);
DISPLAY 0.638298 (90 2725);
FORCEPROP 1 LAST VALUE 4.7K
J 0
(95 2925);
DISPLAY 0.638298 (95 2925);
FORCEPROP 1 LAST TOLERANCE 5%
J 0
(95 2875);
DISPLAY 0.638298 (95 2875);
FORCEPROP 1 LAST WATTAGE 1/16W
J 0
(90 2825);
DISPLAY 0.638298 (90 2825);
FORCEPROP 1 LAST MATERIAL CHIP
J 0
(90 2775);
DISPLAY 0.638298 (90 2775);
FORCEPROP 1 LAST $LOCATION R4130
J 0
(95 2975);
DISPLAY 0.638298 (95 2975);
FORCEPROP 1 LASTPIN (50 2950) $PN 1
J 0
(55 2912);
DISPLAY 0.787234 (55 2912);
FORCEPROP 1 LASTPIN (50 2750) $PN 2
J 0
(55 2760);
DISPLAY 0.787234 (55 2760);
FORCEPROP 2 LAST CDS_LIB pure_quanta
J 0
(50 2850);
PAINT MONO (50 2850);
DISPLAY INVISIBLE (50 2850);
FORCEPROP 1 LAST PATH I21
J 0
(100 3025);
DISPLAY 0.978723 (100 3025);
PAINT WHITE (100 3025);
DISPLAY INVISIBLE (100 3025);
FORCEPROP 2 LAST CDS_LOCATION R4130
J 0
(100 3075);
DISPLAY 1.021277 (100 3075);
DISPLAY INVISIBLE (100 3075);
FORCEPROP 2 LAST $SEC 1
J 0
(100 3075);
DISPLAY 0.680851 (100 3075);
PAINT MONO (100 3075);
DISPLAY INVISIBLE (100 3075);
FORCEPROP 2 LAST CDS_SEC 1
J 0
(100 3075);
DISPLAY 1.021277 (100 3075);
DISPLAY INVISIBLE (100 3075);
FORCEADD OFFPAGE..2
(1175 2675);
FORCEPROP 2 LAST $XR0 215 
J 0
(1364 2675);
DISPLAY 0.638298 (1364 2675);
PAINT MONO (1364 2675);
FORCEPROP 2 LAST PATH I22
J 0
(1375 2725);
DISPLAY 1.021277 (1375 2725);
DISPLAY INVISIBLE (1375 2725);
FORCEPROP 2 LAST CDS_LIB standard
J 0
(1175 2675);
DISPLAY INVISIBLE (1175 2675);
FORCEPROP 1 LAST COMMENT_BODY TRUE
J 0
(1130 2580);
DISPLAY 0.872340 (1130 2580);
PAINT GREEN (1130 2580);
DISPLAY INVISIBLE (1130 2580);
FORCEPROP 1 LAST OFFPAGE TRUE
J 0
(1500 2550);
DISPLAY 0.872340 (1500 2550);
PAINT AQUA (1500 2550);
DISPLAY INVISIBLE (1500 2550);
FORCEADD Q_CAP..1
(825 2375);
FORCEPROP 1 LAST PART_NUMBER TMP_QCH21006JB10
J 0
(875 2225);
DISPLAY 0.638298 (875 2225);
DISPLAY INVISIBLE (875 2225);
FORCEPROP 1 LAST PACK_TYPE 0402
J 0
(875 2175);
DISPLAY 0.638298 (875 2175);
FORCEPROP 1 LAST VALUE 1000PF
J 0
(875 2425);
DISPLAY 0.638298 (875 2425);
FORCEPROP 1 LAST VOLTAGE 50V
J 0
(875 2375);
DISPLAY 0.638298 (875 2375);
FORCEPROP 1 LAST TOLERANCE 5%
J 0
(875 2325);
DISPLAY 0.638298 (875 2325);
FORCEPROP 1 LAST MATERIAL EMPTY
J 0
(875 2275);
DISPLAY 0.638298 (875 2275);
PAINT RED (875 2275);
FORCEPROP 1 LAST $LOCATION C2266
J 0
(875 2475);
DISPLAY 0.978723 (875 2475);
FORCEPROP 1 LASTPIN (825 2475) $PN 1
J 0
(835 2455);
DISPLAY 0.787234 (835 2455);
PAINT MONO (835 2455);
FORCEPROP 1 LASTPIN (825 2275) $PN 2
J 0
(835 2255);
DISPLAY 0.787234 (835 2255);
PAINT MONO (835 2255);
FORCEPROP 1 LAST PATH I23
J 0
(875 2525);
DISPLAY 0.978723 (875 2525);
PAINT WHITE (875 2525);
DISPLAY INVISIBLE (875 2525);
FORCEPROP 2 LAST CDS_LIB pure_quanta
J 0
(825 2375);
DISPLAY INVISIBLE (825 2375);
FORCEPROP 0 LAST CDS_LOCATION C2266
J 0
(875 2525);
DISPLAY 1.021277 (875 2525);
DISPLAY INVISIBLE (875 2525);
FORCEPROP 0 LAST $SEC 1
J 0
(875 2525);
DISPLAY 0.680851 (875 2525);
PAINT MONO (875 2525);
DISPLAY INVISIBLE (875 2525);
FORCEPROP 0 LAST CDS_SEC 1
J 0
(875 2525);
DISPLAY 1.021277 (875 2525);
DISPLAY INVISIBLE (875 2525);
FORCEADD UNIVERSAL_GND..1
(825 2175);
FORCEPROP 3 LASTPIN (825 2225) SIG_NAME GND\g
J 0
(835 2235);
DISPLAY 0.659574 (835 2235);
PAINT MONO (835 2235);
DISPLAY INVISIBLE (835 2235);
FORCEPROP 1 LAST PATH I24
J 0
(900 2175);
DISPLAY 0.872340 (900 2175);
PAINT AQUA (900 2175);
DISPLAY INVISIBLE (900 2175);
FORCEPROP 2 LAST CDS_LIB logical_power
J 0
(825 2175);
DISPLAY INVISIBLE (825 2175);
FORCEPROP 1 LAST HDL_POWER GND
J 1
(850 2100);
DISPLAY 0.872340 (850 2100);
PAINT GREEN (850 2100);
DISPLAY INVISIBLE (850 2100);
FORCEADD UNIVERSAL_GND..1
(50 2050);
FORCEPROP 3 LASTPIN (50 2100) SIG_NAME GND\g
J 0
(60 2110);
DISPLAY 0.659574 (60 2110);
PAINT MONO (60 2110);
DISPLAY INVISIBLE (60 2110);
FORCEPROP 1 LAST PATH I25
J 0
(125 2050);
DISPLAY 0.872340 (125 2050);
PAINT AQUA (125 2050);
DISPLAY INVISIBLE (125 2050);
FORCEPROP 2 LAST CDS_LIB logical_power
J 0
(50 2050);
DISPLAY INVISIBLE (50 2050);
FORCEPROP 1 LAST HDL_POWER GND
J 1
(75 1975);
DISPLAY 0.872340 (75 1975);
PAINT GREEN (75 1975);
DISPLAY INVISIBLE (75 1975);
FORCEADD UNIVERSAL_POWER..1
(-1100 2950);
FORCEPROP 3 LASTPIN (-1100 2900) SIG_NAME P3V3_AUX\g
J 0
(-1090 2910);
DISPLAY 0.659574 (-1090 2910);
PAINT MONO (-1090 2910);
DISPLAY INVISIBLE (-1090 2910);
FORCEPROP 1 LAST HDL_POWER P3V3_AUX
J 1
(-1100 3000);
DISPLAY 0.872340 (-1100 3000);
PAINT GREEN (-1100 3000);
FORCEPROP 1 LAST PATH I26
J 0
(-1050 2975);
DISPLAY 0.872340 (-1050 2975);
PAINT AQUA (-1050 2975);
DISPLAY INVISIBLE (-1050 2975);
FORCEPROP 2 LAST CDS_LIB logical_power
J 0
(-1100 2950);
PAINT MONO (-1100 2950);
DISPLAY INVISIBLE (-1100 2950);
FORCEADD Q_RES..2
(-1100 2725);
FORCEPROP 1 LAST PART_NUMBER CS24702JB10
J 0
(-1060 2550);
DISPLAY 0.638298 (-1060 2550);
DISPLAY INVISIBLE (-1060 2550);
FORCEPROP 1 LAST MATERIAL CHIP
J 0
(-1060 2650);
DISPLAY 0.638298 (-1060 2650);
FORCEPROP 1 LAST WATTAGE 1/16W
J 0
(-1060 2700);
DISPLAY 0.638298 (-1060 2700);
FORCEPROP 1 LAST PACK_TYPE 0402LF
J 0
(-1060 2600);
DISPLAY 0.638298 (-1060 2600);
FORCEPROP 1 LAST TOLERANCE 5%
J 0
(-1055 2750);
DISPLAY 0.638298 (-1055 2750);
FORCEPROP 1 LAST VALUE 4.7K
J 0
(-1055 2800);
DISPLAY 0.638298 (-1055 2800);
FORCEPROP 1 LAST $LOCATION R4127
J 0
(-1055 2850);
DISPLAY 0.638298 (-1055 2850);
FORCEPROP 1 LASTPIN (-1100 2825) $PN 1
J 0
(-1095 2787);
DISPLAY 0.787234 (-1095 2787);
FORCEPROP 1 LASTPIN (-1100 2625) $PN 2
J 0
(-1095 2635);
DISPLAY 0.787234 (-1095 2635);
FORCEPROP 2 LAST CDS_LIB pure_quanta
J 0
(-1100 2725);
PAINT MONO (-1100 2725);
DISPLAY INVISIBLE (-1100 2725);
FORCEPROP 1 LAST PATH I27
J 0
(-1050 2900);
DISPLAY 0.978723 (-1050 2900);
PAINT WHITE (-1050 2900);
DISPLAY INVISIBLE (-1050 2900);
FORCEPROP 2 LAST CDS_LOCATION R4127
J 0
(-1050 2950);
DISPLAY 1.021277 (-1050 2950);
DISPLAY INVISIBLE (-1050 2950);
FORCEPROP 2 LAST $SEC 1
J 0
(-1050 2950);
DISPLAY 0.680851 (-1050 2950);
PAINT MONO (-1050 2950);
DISPLAY INVISIBLE (-1050 2950);
FORCEPROP 2 LAST CDS_SEC 1
J 0
(-1050 2950);
DISPLAY 1.021277 (-1050 2950);
DISPLAY INVISIBLE (-1050 2950);
FORCEADD UNIVERSAL_GND..1
(-1100 1750);
FORCEPROP 3 LASTPIN (-1100 1800) SIG_NAME GND\g
J 0
(-1090 1810);
DISPLAY 0.659574 (-1090 1810);
PAINT MONO (-1090 1810);
DISPLAY INVISIBLE (-1090 1810);
FORCEPROP 1 LAST PATH I28
J 0
(-1025 1750);
DISPLAY 0.872340 (-1025 1750);
PAINT AQUA (-1025 1750);
DISPLAY INVISIBLE (-1025 1750);
FORCEPROP 2 LAST CDS_LIB logical_power
J 0
(-1100 1750);
DISPLAY INVISIBLE (-1100 1750);
FORCEPROP 1 LAST HDL_POWER GND
J 1
(-1075 1675);
DISPLAY 0.872340 (-1075 1675);
PAINT GREEN (-1075 1675);
DISPLAY INVISIBLE (-1075 1675);
FORCEADD MOSFET_NCH_DUAL..1
(-1150 2125);
FORCEPROP 1 LAST PART_NUMBER BAM138K0003
J 0
(-999 2039);
DISPLAY 0.723404 (-999 2039);
PAINT GREEN (-999 2039);
DISPLAY INVISIBLE (-999 2039);
FORCEPROP 2 LAST PART_TYPE SMLF
J 0
(-975 2200);
DISPLAY 1.021277 (-975 2200);
FORCEPROP 1 LAST MATERIAL IC
J 0
(-999 1974);
DISPLAY 0.723404 (-999 1974);
PAINT GREEN (-999 1974);
FORCEPROP 2 LAST VALUE PJT138K
J 0
(-975 2150);
DISPLAY 1.021277 (-975 2150);
FORCEPROP 1 LAST LOCATION Q131
J 0
(-999 2099);
DISPLAY 0.723404 (-999 2099);
PAINT GREEN (-999 2099);
FORCEPROP 0 LASTPIN (-1100 2325) $PN 6
R 1
J 0
(-1110 2335);
DISPLAY 0.680851 (-1110 2335);
PAINT MONO (-1110 2335);
FORCEPROP 0 LASTPIN (-1350 2075) $PN 2
J 2
(-1360 2085);
DISPLAY 0.680851 (-1360 2085);
PAINT MONO (-1360 2085);
FORCEPROP 0 LASTPIN (-1100 1925) $PN 1
R 1
J 2
(-1110 1915);
DISPLAY 0.680851 (-1110 1915);
PAINT MONO (-1110 1915);
FORCEPROP 2 LAST CDS_LIB pure_quanta
J 0
(-1150 2125);
DISPLAY INVISIBLE (-1150 2125);
FORCEPROP 1 LAST NEEDS_NO_SIZE TRUE
J 0
(-1150 2124);
DISPLAY 0.468085 (-1150 2124);
PAINT GREEN (-1150 2124);
DISPLAY INVISIBLE (-1150 2124);
FORCEPROP 1 LAST CDS_LMAN_SYM_OUTLINE -150,150,150,-150
J 0
(-1150 2125);
DISPLAY 0.468085 (-1150 2125);
PAINT GREEN (-1150 2125);
DISPLAY INVISIBLE (-1150 2125);
FORCEPROP 1 LAST PATH I29
J 0
(-1150 2125);
DISPLAY 0.723404 (-1150 2125);
PAINT GREEN (-1150 2125);
DISPLAY INVISIBLE (-1150 2125);
FORCEPROP 0 LAST $SEC 1
J 0
(-975 2250);
DISPLAY 0.680851 (-975 2250);
PAINT MONO (-975 2250);
DISPLAY INVISIBLE (-975 2250);
FORCEPROP 2 LAST CDS_SEC 1
J 0
(-975 2250);
DISPLAY 1.021277 (-975 2250);
DISPLAY INVISIBLE (-975 2250);
FORCEADD UNIVERSAL_GND..1
(800 3550);
FORCEPROP 3 LASTPIN (800 3600) SIG_NAME GND\g
J 0
(810 3610);
DISPLAY 0.659574 (810 3610);
PAINT MONO (810 3610);
DISPLAY INVISIBLE (810 3610);
FORCEPROP 1 LAST PATH I3
J 0
(875 3550);
DISPLAY 0.872340 (875 3550);
PAINT AQUA (875 3550);
DISPLAY INVISIBLE (875 3550);
FORCEPROP 2 LAST CDS_LIB logical_power
J 0
(800 3550);
DISPLAY INVISIBLE (800 3550);
FORCEPROP 1 LAST HDL_POWER GND
J 1
(825 3475);
DISPLAY 0.872340 (825 3475);
PAINT GREEN (825 3475);
DISPLAY INVISIBLE (825 3475);
FORCEADD UNIVERSAL_POWER..1
(-2275 2600);
FORCEPROP 3 LASTPIN (-2275 2550) SIG_NAME P3V3_AUX\g
J 0
(-2265 2560);
DISPLAY 0.659574 (-2265 2560);
PAINT MONO (-2265 2560);
DISPLAY INVISIBLE (-2265 2560);
FORCEPROP 1 LAST HDL_POWER P3V3_AUX
J 1
(-2275 2650);
DISPLAY 0.872340 (-2275 2650);
PAINT GREEN (-2275 2650);
FORCEPROP 1 LAST PATH I30
J 0
(-2225 2625);
DISPLAY 0.872340 (-2225 2625);
PAINT AQUA (-2225 2625);
DISPLAY INVISIBLE (-2225 2625);
FORCEPROP 2 LAST CDS_LIB logical_power
J 0
(-2275 2600);
PAINT MONO (-2275 2600);
DISPLAY INVISIBLE (-2275 2600);
FORCEADD Q_RES..2
(-2275 2350);
FORCEPROP 1 LAST PART_NUMBER CS35492FB03
J 0
(-2235 2225);
DISPLAY 0.787234 (-2235 2225);
DISPLAY INVISIBLE (-2235 2225);
FORCEPROP 1 LAST WATTAGE 1/16W
J 0
(-2235 2325);
DISPLAY 0.787234 (-2235 2325);
FORCEPROP 1 LAST MATERIAL EMPTY
J 0
(-2235 2275);
DISPLAY 0.787234 (-2235 2275);
PAINT RED (-2235 2275);
FORCEPROP 1 LAST PACK_TYPE 0402LF
J 0
(-2235 2175);
DISPLAY 0.787234 (-2235 2175);
FORCEPROP 1 LAST TOLERANCE 1%
J 0
(-2230 2375);
DISPLAY 0.787234 (-2230 2375);
FORCEPROP 1 LAST VALUE 54.9K
J 0
(-2230 2425);
DISPLAY 0.787234 (-2230 2425);
FORCEPROP 1 LAST $LOCATION R4123
J 0
(-2230 2475);
DISPLAY 0.978723 (-2230 2475);
FORCEPROP 1 LASTPIN (-2275 2450) $PN 1
J 0
(-2270 2412);
DISPLAY 0.787234 (-2270 2412);
PAINT MONO (-2270 2412);
FORCEPROP 1 LASTPIN (-2275 2250) $PN 2
J 0
(-2270 2260);
DISPLAY 0.787234 (-2270 2260);
PAINT MONO (-2270 2260);
FORCEPROP 2 LAST CDS_LIB pure_quanta
J 0
(-2275 2350);
DISPLAY INVISIBLE (-2275 2350);
FORCEPROP 1 LAST PATH I31
J 0
(-2225 2525);
DISPLAY 0.978723 (-2225 2525);
PAINT WHITE (-2225 2525);
DISPLAY INVISIBLE (-2225 2525);
FORCEPROP 0 LAST CDS_LOCATION R4123
J 0
(-2225 2525);
DISPLAY 1.021277 (-2225 2525);
DISPLAY INVISIBLE (-2225 2525);
FORCEPROP 0 LAST $SEC 1
J 0
(-2225 2525);
DISPLAY 0.680851 (-2225 2525);
PAINT MONO (-2225 2525);
DISPLAY INVISIBLE (-2225 2525);
FORCEPROP 0 LAST CDS_SEC 1
J 0
(-2225 2525);
DISPLAY 1.021277 (-2225 2525);
DISPLAY INVISIBLE (-2225 2525);
FORCEADD Q_RES..2
(-2250 1875);
FORCEPROP 1 LAST PART_NUMBER CS41002FB09
J 0
(-2210 1750);
DISPLAY 0.510638 (-2210 1750);
DISPLAY INVISIBLE (-2210 1750);
FORCEPROP 1 LAST MATERIAL EMPTY
J 0
(-2210 1800);
DISPLAY 0.510638 (-2210 1800);
PAINT RED (-2210 1800);
FORCEPROP 1 LAST TOLERANCE 1%
J 0
(-2205 1900);
DISPLAY 0.510638 (-2205 1900);
FORCEPROP 1 LAST VALUE 100K
J 0
(-2205 1950);
DISPLAY 0.510638 (-2205 1950);
FORCEPROP 1 LAST PACK_TYPE 0402LF
J 0
(-2210 1700);
DISPLAY 0.510638 (-2210 1700);
FORCEPROP 1 LAST WATTAGE 1/16W
J 0
(-2210 1850);
DISPLAY 0.510638 (-2210 1850);
FORCEPROP 1 LAST $LOCATION R4124
J 0
(-2205 2000);
DISPLAY 0.978723 (-2205 2000);
FORCEPROP 1 LASTPIN (-2250 1975) $PN 1
J 0
(-2245 1937);
DISPLAY 0.787234 (-2245 1937);
PAINT MONO (-2245 1937);
FORCEPROP 1 LASTPIN (-2250 1775) $PN 2
J 0
(-2245 1785);
DISPLAY 0.787234 (-2245 1785);
PAINT MONO (-2245 1785);
FORCEPROP 2 LAST CDS_LIB pure_quanta
J 0
(-2250 1875);
DISPLAY INVISIBLE (-2250 1875);
FORCEPROP 1 LAST PATH I32
J 0
(-2200 2050);
DISPLAY 0.978723 (-2200 2050);
PAINT WHITE (-2200 2050);
DISPLAY INVISIBLE (-2200 2050);
FORCEPROP 0 LAST CDS_LOCATION R4124
J 0
(-2200 2050);
DISPLAY 1.021277 (-2200 2050);
DISPLAY INVISIBLE (-2200 2050);
FORCEPROP 0 LAST $SEC 1
J 0
(-2200 2050);
DISPLAY 0.680851 (-2200 2050);
PAINT MONO (-2200 2050);
DISPLAY INVISIBLE (-2200 2050);
FORCEPROP 0 LAST CDS_SEC 1
J 0
(-2200 2050);
DISPLAY 1.021277 (-2200 2050);
DISPLAY INVISIBLE (-2200 2050);
FORCEADD OFFPAGE..4
R 2
(-2525 2075);
FORCEPROP 2 LAST $XR0 140 
J 0
(-2777 2075);
DISPLAY 0.638298 (-2777 2075);
PAINT MONO (-2777 2075);
FORCEPROP 2 LAST PATH I33
J 0
(-2800 2125);
DISPLAY 1.021277 (-2800 2125);
DISPLAY INVISIBLE (-2800 2125);
FORCEPROP 1 LAST OFFPAGE TRUE
J 2
(-2850 1950);
DISPLAY 0.872340 (-2850 1950);
PAINT GREEN (-2850 1950);
DISPLAY INVISIBLE (-2850 1950);
FORCEPROP 1 LAST COMMENT_BODY TRUE
J 2
(-2500 1975);
DISPLAY 0.872340 (-2500 1975);
PAINT GREEN (-2500 1975);
DISPLAY INVISIBLE (-2500 1975);
FORCEPROP 2 LAST CDS_LIB standard
J 0
(-2525 2075);
DISPLAY INVISIBLE (-2525 2075);
FORCEADD UNIVERSAL_GND..1
(-2250 1600);
FORCEPROP 3 LASTPIN (-2250 1650) SIG_NAME GND\g
J 0
(-2240 1660);
DISPLAY 0.659574 (-2240 1660);
PAINT MONO (-2240 1660);
DISPLAY INVISIBLE (-2240 1660);
FORCEPROP 2 LAST CDS_LIB logical_power
J 0
(-2250 1600);
DISPLAY INVISIBLE (-2250 1600);
FORCEPROP 1 LAST HDL_POWER GND
J 1
(-2225 1525);
DISPLAY 0.872340 (-2225 1525);
PAINT GREEN (-2225 1525);
DISPLAY INVISIBLE (-2225 1525);
FORCEPROP 1 LAST PATH I34
J 0
(-2175 1600);
DISPLAY 0.872340 (-2175 1600);
PAINT AQUA (-2175 1600);
DISPLAY INVISIBLE (-2175 1600);
FORCEADD MOSFET_NCH_DUAL..2
(-25 975);
FORCEPROP 1 LAST PART_NUMBER BAM138K0003
J 0
(126 881);
DISPLAY 0.723404 (126 881);
PAINT GREEN (126 881);
DISPLAY INVISIBLE (126 881);
FORCEPROP 2 LAST PART_TYPE SMLF
J 0
(150 1050);
DISPLAY 1.021277 (150 1050);
FORCEPROP 2 LAST VALUE PJT138K
J 0
(150 1000);
DISPLAY 1.021277 (150 1000);
FORCEPROP 1 LAST MATERIAL IC
J 0
(126 826);
DISPLAY 0.723404 (126 826);
PAINT GREEN (126 826);
FORCEPROP 1 LAST $LOCATION Q132
J 0
(126 951);
DISPLAY 0.723404 (126 951);
PAINT GREEN (126 951);
FORCEPROP 0 LASTPIN (25 1175) $PN 3
R 1
J 0
(15 1185);
DISPLAY 0.680851 (15 1185);
PAINT MONO (15 1185);
FORCEPROP 0 LASTPIN (-225 925) $PN 5
J 2
(-235 935);
DISPLAY 0.680851 (-235 935);
PAINT MONO (-235 935);
FORCEPROP 0 LASTPIN (25 775) $PN 4
R 1
J 2
(15 765);
DISPLAY 0.680851 (15 765);
PAINT MONO (15 765);
FORCEPROP 2 LAST CDS_LIB pure_quanta
J 0
(-25 975);
DISPLAY INVISIBLE (-25 975);
FORCEPROP 1 LAST NEEDS_NO_SIZE TRUE
J 0
(125 866);
DISPLAY 0.468085 (125 866);
PAINT GREEN (125 866);
DISPLAY INVISIBLE (125 866);
FORCEPROP 1 LAST CDS_LMAN_SYM_OUTLINE -150,150,150,-150
J 0
(-25 975);
DISPLAY 0.468085 (-25 975);
PAINT GREEN (-25 975);
DISPLAY INVISIBLE (-25 975);
FORCEPROP 1 LAST PATH I35
J 0
(125 825);
DISPLAY 0.723404 (125 825);
PAINT GREEN (125 825);
DISPLAY INVISIBLE (125 825);
FORCEPROP 0 LAST CDS_LOCATION Q132
J 0
(150 1100);
DISPLAY 1.021277 (150 1100);
DISPLAY INVISIBLE (150 1100);
FORCEPROP 0 LAST $SEC 2
J 0
(150 1100);
DISPLAY 0.680851 (150 1100);
PAINT MONO (150 1100);
DISPLAY INVISIBLE (150 1100);
FORCEPROP 0 LAST CDS_SEC 2
J 0
(150 1100);
DISPLAY 1.021277 (150 1100);
DISPLAY INVISIBLE (150 1100);
FORCEADD Q_RES..2
(25 1400);
FORCEPROP 1 LAST PART_NUMBER CS24702JB10
J 0
(65 1225);
DISPLAY 0.638298 (65 1225);
DISPLAY INVISIBLE (65 1225);
FORCEPROP 1 LAST MATERIAL CHIP
J 0
(65 1325);
DISPLAY 0.638298 (65 1325);
FORCEPROP 1 LAST VALUE 4.7K
J 0
(70 1475);
DISPLAY 0.638298 (70 1475);
FORCEPROP 1 LAST WATTAGE 1/16W
J 0
(65 1375);
DISPLAY 0.638298 (65 1375);
FORCEPROP 1 LAST TOLERANCE 5%
J 0
(70 1425);
DISPLAY 0.638298 (70 1425);
FORCEPROP 1 LAST PACK_TYPE 0402LF
J 0
(65 1275);
DISPLAY 0.638298 (65 1275);
FORCEPROP 1 LAST $LOCATION R4129
J 0
(70 1525);
DISPLAY 0.638298 (70 1525);
FORCEPROP 1 LASTPIN (25 1500) $PN 1
J 0
(30 1462);
DISPLAY 0.787234 (30 1462);
FORCEPROP 1 LASTPIN (25 1300) $PN 2
J 0
(30 1310);
DISPLAY 0.787234 (30 1310);
FORCEPROP 2 LAST CDS_LIB pure_quanta
J 0
(25 1400);
PAINT MONO (25 1400);
DISPLAY INVISIBLE (25 1400);
FORCEPROP 1 LAST PATH I36
J 0
(75 1575);
DISPLAY 0.978723 (75 1575);
PAINT WHITE (75 1575);
DISPLAY INVISIBLE (75 1575);
FORCEPROP 2 LAST CDS_LOCATION R4129
J 0
(75 1625);
DISPLAY 1.021277 (75 1625);
DISPLAY INVISIBLE (75 1625);
FORCEPROP 2 LAST $SEC 1
J 0
(75 1625);
DISPLAY 0.680851 (75 1625);
PAINT MONO (75 1625);
DISPLAY INVISIBLE (75 1625);
FORCEPROP 2 LAST CDS_SEC 1
J 0
(75 1625);
DISPLAY 1.021277 (75 1625);
DISPLAY INVISIBLE (75 1625);
FORCEADD UNIVERSAL_POWER..1
(25 1625);
FORCEPROP 3 LASTPIN (25 1575) SIG_NAME P3V3_AUX\g
J 0
(35 1585);
DISPLAY 0.659574 (35 1585);
PAINT MONO (35 1585);
DISPLAY INVISIBLE (35 1585);
FORCEPROP 1 LAST HDL_POWER P3V3_AUX
J 1
(25 1675);
DISPLAY 0.872340 (25 1675);
PAINT GREEN (25 1675);
FORCEPROP 1 LAST PATH I37
J 0
(75 1650);
DISPLAY 0.872340 (75 1650);
PAINT AQUA (75 1650);
DISPLAY INVISIBLE (75 1650);
FORCEPROP 2 LAST CDS_LIB logical_power
J 0
(25 1625);
PAINT MONO (25 1625);
DISPLAY INVISIBLE (25 1625);
FORCEADD UNIVERSAL_POWER..1
(-1125 1500);
FORCEPROP 3 LASTPIN (-1125 1450) SIG_NAME P3V3_AUX\g
J 0
(-1115 1460);
DISPLAY 0.659574 (-1115 1460);
PAINT MONO (-1115 1460);
DISPLAY INVISIBLE (-1115 1460);
FORCEPROP 1 LAST HDL_POWER P3V3_AUX
J 1
(-1125 1550);
DISPLAY 0.872340 (-1125 1550);
PAINT GREEN (-1125 1550);
FORCEPROP 1 LAST PATH I38
J 0
(-1075 1525);
DISPLAY 0.872340 (-1075 1525);
PAINT AQUA (-1075 1525);
DISPLAY INVISIBLE (-1075 1525);
FORCEPROP 2 LAST CDS_LIB logical_power
J 0
(-1125 1500);
PAINT MONO (-1125 1500);
DISPLAY INVISIBLE (-1125 1500);
FORCEADD OFFPAGE..2
(1150 1225);
FORCEPROP 2 LAST $XR1 227 
J 0
(1459 1225);
DISPLAY 0.638298 (1459 1225);
PAINT MONO (1459 1225);
FORCEPROP 2 LAST $XR0 215 
J 0
(1339 1225);
DISPLAY 0.638298 (1339 1225);
PAINT MONO (1339 1225);
FORCEPROP 2 LAST PATH I39
J 0
(1350 1275);
DISPLAY 1.021277 (1350 1275);
DISPLAY INVISIBLE (1350 1275);
FORCEPROP 1 LAST OFFPAGE TRUE
J 0
(1475 1100);
DISPLAY 0.872340 (1475 1100);
PAINT AQUA (1475 1100);
DISPLAY INVISIBLE (1475 1100);
FORCEPROP 1 LAST COMMENT_BODY TRUE
J 0
(1105 1130);
DISPLAY 0.872340 (1105 1130);
PAINT GREEN (1105 1130);
DISPLAY INVISIBLE (1105 1130);
FORCEPROP 2 LAST CDS_LIB standard
J 0
(1150 1225);
DISPLAY INVISIBLE (1150 1225);
FORCEADD UNIVERSAL_POWER..1
(25 4450);
FORCEPROP 3 LASTPIN (25 4400) SIG_NAME P3V3_AUX\g
J 0
(35 4410);
DISPLAY 0.659574 (35 4410);
PAINT MONO (35 4410);
DISPLAY INVISIBLE (35 4410);
FORCEPROP 1 LAST HDL_POWER P3V3_AUX
J 1
(25 4500);
DISPLAY 0.872340 (25 4500);
PAINT GREEN (25 4500);
FORCEPROP 1 LAST PATH I4
J 0
(75 4475);
DISPLAY 0.872340 (75 4475);
PAINT AQUA (75 4475);
DISPLAY INVISIBLE (75 4475);
FORCEPROP 2 LAST CDS_LIB logical_power
J 0
(25 4450);
PAINT MONO (25 4450);
DISPLAY INVISIBLE (25 4450);
FORCEADD Q_CAP..1
(800 925);
FORCEPROP 1 LAST PART_NUMBER TMP_QCH21006JB10
J 0
(850 775);
DISPLAY 0.638298 (850 775);
DISPLAY INVISIBLE (850 775);
FORCEPROP 1 LAST PACK_TYPE 0402
J 0
(850 725);
DISPLAY 0.638298 (850 725);
FORCEPROP 1 LAST MATERIAL EMPTY
J 0
(850 825);
DISPLAY 0.638298 (850 825);
PAINT RED (850 825);
FORCEPROP 1 LAST TOLERANCE 5%
J 0
(850 875);
DISPLAY 0.638298 (850 875);
FORCEPROP 1 LAST VOLTAGE 50V
J 0
(850 925);
DISPLAY 0.638298 (850 925);
FORCEPROP 1 LAST VALUE 1000PF
J 0
(850 975);
DISPLAY 0.638298 (850 975);
FORCEPROP 1 LAST $LOCATION C2265
J 0
(850 1025);
DISPLAY 0.978723 (850 1025);
FORCEPROP 1 LASTPIN (800 1025) $PN 1
J 0
(810 1005);
DISPLAY 0.787234 (810 1005);
PAINT MONO (810 1005);
FORCEPROP 1 LASTPIN (800 825) $PN 2
J 0
(810 805);
DISPLAY 0.787234 (810 805);
PAINT MONO (810 805);
FORCEPROP 1 LAST PATH I40
J 0
(850 1075);
DISPLAY 0.978723 (850 1075);
PAINT WHITE (850 1075);
DISPLAY INVISIBLE (850 1075);
FORCEPROP 2 LAST CDS_LIB pure_quanta
J 0
(800 925);
DISPLAY INVISIBLE (800 925);
FORCEPROP 0 LAST CDS_LOCATION C2265
J 0
(850 1075);
DISPLAY 1.021277 (850 1075);
DISPLAY INVISIBLE (850 1075);
FORCEPROP 0 LAST $SEC 1
J 0
(850 1075);
DISPLAY 0.680851 (850 1075);
PAINT MONO (850 1075);
DISPLAY INVISIBLE (850 1075);
FORCEPROP 0 LAST CDS_SEC 1
J 0
(850 1075);
DISPLAY 1.021277 (850 1075);
DISPLAY INVISIBLE (850 1075);
FORCEADD UNIVERSAL_GND..1
(800 725);
FORCEPROP 3 LASTPIN (800 775) SIG_NAME GND\g
J 0
(810 785);
DISPLAY 0.659574 (810 785);
PAINT MONO (810 785);
DISPLAY INVISIBLE (810 785);
FORCEPROP 1 LAST PATH I41
J 0
(875 725);
DISPLAY 0.872340 (875 725);
PAINT AQUA (875 725);
DISPLAY INVISIBLE (875 725);
FORCEPROP 1 LAST HDL_POWER GND
J 1
(825 650);
DISPLAY 0.872340 (825 650);
PAINT GREEN (825 650);
DISPLAY INVISIBLE (825 650);
FORCEPROP 2 LAST CDS_LIB logical_power
J 0
(800 725);
DISPLAY INVISIBLE (800 725);
FORCEADD UNIVERSAL_GND..1
(25 600);
FORCEPROP 3 LASTPIN (25 650) SIG_NAME GND\g
J 0
(35 660);
DISPLAY 0.659574 (35 660);
PAINT MONO (35 660);
DISPLAY INVISIBLE (35 660);
FORCEPROP 1 LAST PATH I42
J 0
(100 600);
DISPLAY 0.872340 (100 600);
PAINT AQUA (100 600);
DISPLAY INVISIBLE (100 600);
FORCEPROP 1 LAST HDL_POWER GND
J 1
(50 525);
DISPLAY 0.872340 (50 525);
PAINT GREEN (50 525);
DISPLAY INVISIBLE (50 525);
FORCEPROP 2 LAST CDS_LIB logical_power
J 0
(25 600);
DISPLAY INVISIBLE (25 600);
FORCEADD Q_RES..2
(-1125 1275);
FORCEPROP 1 LAST PART_NUMBER CS24702JB10
J 0
(-1085 1100);
DISPLAY 0.638298 (-1085 1100);
DISPLAY INVISIBLE (-1085 1100);
FORCEPROP 1 LAST WATTAGE 1/16W
J 0
(-1085 1250);
DISPLAY 0.638298 (-1085 1250);
FORCEPROP 1 LAST TOLERANCE 5%
J 0
(-1080 1300);
DISPLAY 0.638298 (-1080 1300);
FORCEPROP 1 LAST MATERIAL CHIP
J 0
(-1085 1200);
DISPLAY 0.638298 (-1085 1200);
FORCEPROP 1 LAST PACK_TYPE 0402LF
J 0
(-1085 1150);
DISPLAY 0.638298 (-1085 1150);
FORCEPROP 1 LAST VALUE 4.7K
J 0
(-1080 1350);
DISPLAY 0.638298 (-1080 1350);
FORCEPROP 1 LAST $LOCATION R4126
J 0
(-1080 1400);
DISPLAY 0.638298 (-1080 1400);
FORCEPROP 1 LASTPIN (-1125 1375) $PN 1
J 0
(-1120 1337);
DISPLAY 0.787234 (-1120 1337);
FORCEPROP 1 LASTPIN (-1125 1175) $PN 2
J 0
(-1120 1185);
DISPLAY 0.787234 (-1120 1185);
FORCEPROP 2 LAST CDS_LIB pure_quanta
J 0
(-1125 1275);
PAINT MONO (-1125 1275);
DISPLAY INVISIBLE (-1125 1275);
FORCEPROP 1 LAST PATH I43
J 0
(-1075 1450);
DISPLAY 0.978723 (-1075 1450);
PAINT WHITE (-1075 1450);
DISPLAY INVISIBLE (-1075 1450);
FORCEPROP 2 LAST CDS_LOCATION R4126
J 0
(-1075 1500);
DISPLAY 1.021277 (-1075 1500);
DISPLAY INVISIBLE (-1075 1500);
FORCEPROP 2 LAST $SEC 1
J 0
(-1075 1500);
DISPLAY 0.680851 (-1075 1500);
PAINT MONO (-1075 1500);
DISPLAY INVISIBLE (-1075 1500);
FORCEPROP 2 LAST CDS_SEC 1
J 0
(-1075 1500);
DISPLAY 1.021277 (-1075 1500);
DISPLAY INVISIBLE (-1075 1500);
FORCEADD MOSFET_NCH_DUAL..1
(-1175 675);
FORCEPROP 1 LAST PART_NUMBER BAM138K0003
J 0
(-1024 589);
DISPLAY 0.723404 (-1024 589);
PAINT GREEN (-1024 589);
DISPLAY INVISIBLE (-1024 589);
FORCEPROP 1 LAST MATERIAL IC
J 0
(-1024 524);
DISPLAY 0.723404 (-1024 524);
PAINT GREEN (-1024 524);
FORCEPROP 2 LAST PART_TYPE SMLF
J 0
(-1000 750);
DISPLAY 1.021277 (-1000 750);
FORCEPROP 2 LAST VALUE PJT138K
J 0
(-1000 700);
DISPLAY 1.021277 (-1000 700);
FORCEPROP 1 LAST LOCATION Q132
J 0
(-1024 649);
DISPLAY 0.723404 (-1024 649);
PAINT GREEN (-1024 649);
FORCEPROP 0 LASTPIN (-1125 875) $PN 6
R 1
J 0
(-1135 885);
DISPLAY 0.680851 (-1135 885);
PAINT MONO (-1135 885);
FORCEPROP 0 LASTPIN (-1375 625) $PN 2
J 2
(-1385 635);
DISPLAY 0.680851 (-1385 635);
PAINT MONO (-1385 635);
FORCEPROP 0 LASTPIN (-1125 475) $PN 1
R 1
J 2
(-1135 465);
DISPLAY 0.680851 (-1135 465);
PAINT MONO (-1135 465);
FORCEPROP 1 LAST CDS_LMAN_SYM_OUTLINE -150,150,150,-150
J 0
(-1175 675);
DISPLAY 0.468085 (-1175 675);
PAINT GREEN (-1175 675);
DISPLAY INVISIBLE (-1175 675);
FORCEPROP 1 LAST NEEDS_NO_SIZE TRUE
J 0
(-1175 674);
DISPLAY 0.468085 (-1175 674);
PAINT GREEN (-1175 674);
DISPLAY INVISIBLE (-1175 674);
FORCEPROP 2 LAST CDS_LIB pure_quanta
J 0
(-1175 675);
DISPLAY INVISIBLE (-1175 675);
FORCEPROP 1 LAST PATH I44
J 0
(-1175 675);
DISPLAY 0.723404 (-1175 675);
PAINT GREEN (-1175 675);
DISPLAY INVISIBLE (-1175 675);
FORCEPROP 0 LAST $SEC 1
J 0
(-1000 800);
DISPLAY 0.680851 (-1000 800);
PAINT MONO (-1000 800);
DISPLAY INVISIBLE (-1000 800);
FORCEPROP 2 LAST CDS_SEC 1
J 0
(-1000 800);
DISPLAY 1.021277 (-1000 800);
DISPLAY INVISIBLE (-1000 800);
FORCEADD UNIVERSAL_GND..1
(-1125 300);
FORCEPROP 3 LASTPIN (-1125 350) SIG_NAME GND\g
J 0
(-1115 360);
DISPLAY 0.659574 (-1115 360);
PAINT MONO (-1115 360);
DISPLAY INVISIBLE (-1115 360);
FORCEPROP 1 LAST PATH I45
J 0
(-1050 300);
DISPLAY 0.872340 (-1050 300);
PAINT AQUA (-1050 300);
DISPLAY INVISIBLE (-1050 300);
FORCEPROP 1 LAST HDL_POWER GND
J 1
(-1100 225);
DISPLAY 0.872340 (-1100 225);
PAINT GREEN (-1100 225);
DISPLAY INVISIBLE (-1100 225);
FORCEPROP 2 LAST CDS_LIB logical_power
J 0
(-1125 300);
DISPLAY INVISIBLE (-1125 300);
FORCEADD UNIVERSAL_POWER..1
(-2300 1150);
FORCEPROP 3 LASTPIN (-2300 1100) SIG_NAME P3V3_AUX\g
J 0
(-2290 1110);
DISPLAY 0.659574 (-2290 1110);
PAINT MONO (-2290 1110);
DISPLAY INVISIBLE (-2290 1110);
FORCEPROP 1 LAST HDL_POWER P3V3_AUX
J 1
(-2300 1200);
DISPLAY 0.872340 (-2300 1200);
PAINT GREEN (-2300 1200);
FORCEPROP 1 LAST PATH I46
J 0
(-2250 1175);
DISPLAY 0.872340 (-2250 1175);
PAINT AQUA (-2250 1175);
DISPLAY INVISIBLE (-2250 1175);
FORCEPROP 2 LAST CDS_LIB logical_power
J 0
(-2300 1150);
PAINT MONO (-2300 1150);
DISPLAY INVISIBLE (-2300 1150);
FORCEADD OFFPAGE..4
R 2
(-2550 625);
FORCEPROP 2 LAST $XR0 140 
J 0
(-2832 625);
DISPLAY 0.638298 (-2832 625);
PAINT MONO (-2832 625);
FORCEPROP 2 LAST PATH I48
J 0
(-2825 675);
DISPLAY 1.021277 (-2825 675);
DISPLAY INVISIBLE (-2825 675);
FORCEPROP 2 LAST CDS_LIB standard
J 0
(-2550 625);
DISPLAY INVISIBLE (-2550 625);
FORCEPROP 1 LAST COMMENT_BODY TRUE
J 2
(-2525 525);
DISPLAY 0.872340 (-2525 525);
PAINT GREEN (-2525 525);
DISPLAY INVISIBLE (-2525 525);
FORCEPROP 1 LAST OFFPAGE TRUE
J 2
(-2875 500);
DISPLAY 0.872340 (-2875 500);
PAINT GREEN (-2875 500);
DISPLAY INVISIBLE (-2875 500);
FORCEADD Q_RES..2
(-2275 425);
FORCEPROP 1 LAST PART_NUMBER CS41002FB09
J 0
(-2235 300);
DISPLAY 0.510638 (-2235 300);
DISPLAY INVISIBLE (-2235 300);
FORCEPROP 1 LAST VALUE 100K
J 0
(-2230 500);
DISPLAY 0.510638 (-2230 500);
FORCEPROP 1 LAST PACK_TYPE 0402LF
J 0
(-2235 250);
DISPLAY 0.510638 (-2235 250);
FORCEPROP 1 LAST WATTAGE 1/16W
J 0
(-2235 400);
DISPLAY 0.510638 (-2235 400);
FORCEPROP 1 LAST TOLERANCE 1%
J 0
(-2230 450);
DISPLAY 0.510638 (-2230 450);
FORCEPROP 1 LAST MATERIAL EMPTY
J 0
(-2235 350);
DISPLAY 0.510638 (-2235 350);
PAINT RED (-2235 350);
FORCEPROP 1 LAST $LOCATION R4122
J 0
(-2230 550);
DISPLAY 0.978723 (-2230 550);
FORCEPROP 1 LASTPIN (-2275 525) $PN 1
J 0
(-2270 487);
DISPLAY 0.787234 (-2270 487);
PAINT MONO (-2270 487);
FORCEPROP 1 LASTPIN (-2275 325) $PN 2
J 0
(-2270 335);
DISPLAY 0.787234 (-2270 335);
PAINT MONO (-2270 335);
FORCEPROP 2 LAST CDS_LIB pure_quanta
J 0
(-2275 425);
DISPLAY INVISIBLE (-2275 425);
FORCEPROP 1 LAST PATH I49
J 0
(-2225 600);
DISPLAY 0.978723 (-2225 600);
PAINT WHITE (-2225 600);
DISPLAY INVISIBLE (-2225 600);
FORCEPROP 0 LAST CDS_LOCATION R4122
J 0
(-2225 600);
DISPLAY 1.021277 (-2225 600);
DISPLAY INVISIBLE (-2225 600);
FORCEPROP 0 LAST $SEC 1
J 0
(-2225 600);
DISPLAY 0.680851 (-2225 600);
PAINT MONO (-2225 600);
DISPLAY INVISIBLE (-2225 600);
FORCEPROP 0 LAST CDS_SEC 1
J 0
(-2225 600);
DISPLAY 1.021277 (-2225 600);
DISPLAY INVISIBLE (-2225 600);
FORCEADD Q_RES..2
(25 4225);
FORCEPROP 1 LAST PART_NUMBER CS24702JB10
J 0
(65 4050);
DISPLAY 0.638298 (65 4050);
DISPLAY INVISIBLE (65 4050);
FORCEPROP 1 LAST TOLERANCE 5%
J 0
(70 4250);
DISPLAY 0.638298 (70 4250);
FORCEPROP 1 LAST WATTAGE 1/16W
J 0
(65 4200);
DISPLAY 0.638298 (65 4200);
FORCEPROP 1 LAST VALUE 4.7K
J 0
(70 4300);
DISPLAY 0.638298 (70 4300);
FORCEPROP 1 LAST MATERIAL CHIP
J 0
(65 4150);
DISPLAY 0.638298 (65 4150);
FORCEPROP 1 LAST PACK_TYPE 0402LF
J 0
(65 4100);
DISPLAY 0.638298 (65 4100);
FORCEPROP 1 LAST $LOCATION R4128
J 0
(70 4350);
DISPLAY 0.638298 (70 4350);
FORCEPROP 1 LASTPIN (25 4325) $PN 1
J 0
(30 4287);
DISPLAY 0.787234 (30 4287);
FORCEPROP 1 LASTPIN (25 4125) $PN 2
J 0
(30 4135);
DISPLAY 0.787234 (30 4135);
FORCEPROP 2 LAST CDS_LIB pure_quanta
J 0
(25 4225);
PAINT MONO (25 4225);
DISPLAY INVISIBLE (25 4225);
FORCEPROP 1 LAST PATH I5
J 0
(75 4400);
DISPLAY 0.978723 (75 4400);
PAINT WHITE (75 4400);
DISPLAY INVISIBLE (75 4400);
FORCEPROP 2 LAST CDS_LOCATION R4128
J 0
(75 4450);
DISPLAY 1.021277 (75 4450);
DISPLAY INVISIBLE (75 4450);
FORCEPROP 2 LAST $SEC 1
J 0
(75 4450);
DISPLAY 0.680851 (75 4450);
PAINT MONO (75 4450);
DISPLAY INVISIBLE (75 4450);
FORCEPROP 2 LAST CDS_SEC 1
J 0
(75 4450);
DISPLAY 1.021277 (75 4450);
DISPLAY INVISIBLE (75 4450);
FORCEADD UNIVERSAL_GND..1
(-2275 150);
FORCEPROP 3 LASTPIN (-2275 200) SIG_NAME GND\g
J 0
(-2265 210);
DISPLAY 0.659574 (-2265 210);
PAINT MONO (-2265 210);
DISPLAY INVISIBLE (-2265 210);
FORCEPROP 1 LAST HDL_POWER GND
J 1
(-2250 75);
DISPLAY 0.872340 (-2250 75);
PAINT GREEN (-2250 75);
DISPLAY INVISIBLE (-2250 75);
FORCEPROP 2 LAST CDS_LIB logical_power
J 0
(-2275 150);
DISPLAY INVISIBLE (-2275 150);
FORCEPROP 1 LAST PATH I50
J 0
(-2200 150);
DISPLAY 0.872340 (-2200 150);
PAINT AQUA (-2200 150);
DISPLAY INVISIBLE (-2200 150);
FORCEADD UNIVERSAL_POWER..1
(4650 4750);
FORCEPROP 3 LASTPIN (4650 4700) SIG_NAME P3V3_AUX\g
J 0
(4660 4710);
DISPLAY 0.659574 (4660 4710);
PAINT MONO (4660 4710);
DISPLAY INVISIBLE (4660 4710);
FORCEPROP 1 LAST HDL_POWER P3V3_AUX
J 1
(4650 4800);
DISPLAY 0.872340 (4650 4800);
PAINT GREEN (4650 4800);
FORCEPROP 2 LAST CDS_LIB logical_power
J 0
(4650 4750);
PAINT MONO (4650 4750);
DISPLAY INVISIBLE (4650 4750);
FORCEPROP 1 LAST PATH I51
J 0
(4700 4775);
DISPLAY 0.872340 (4700 4775);
PAINT AQUA (4700 4775);
DISPLAY INVISIBLE (4700 4775);
FORCEADD Q_RES..2
(4650 4525);
FORCEPROP 1 LAST PART_NUMBER CS24702JB10
J 0
(4690 4350);
DISPLAY 0.638298 (4690 4350);
DISPLAY INVISIBLE (4690 4350);
FORCEPROP 1 LAST VALUE 4.7K
J 0
(4695 4600);
DISPLAY 0.638298 (4695 4600);
FORCEPROP 1 LAST WATTAGE 1/16W
J 0
(4690 4500);
DISPLAY 0.638298 (4690 4500);
FORCEPROP 1 LAST TOLERANCE 5%
J 0
(4695 4550);
DISPLAY 0.638298 (4695 4550);
FORCEPROP 1 LAST PACK_TYPE 0402LF
J 0
(4690 4400);
DISPLAY 0.638298 (4690 4400);
FORCEPROP 1 LAST MATERIAL CHIP
J 0
(4690 4450);
DISPLAY 0.638298 (4690 4450);
FORCEPROP 1 LAST $LOCATION R4140
J 0
(4695 4650);
DISPLAY 0.638298 (4695 4650);
FORCEPROP 1 LASTPIN (4650 4625) $PN 1
J 0
(4655 4587);
DISPLAY 0.787234 (4655 4587);
FORCEPROP 1 LASTPIN (4650 4425) $PN 2
J 0
(4655 4435);
DISPLAY 0.787234 (4655 4435);
FORCEPROP 1 LAST PATH I52
J 0
(4700 4700);
DISPLAY 0.978723 (4700 4700);
PAINT WHITE (4700 4700);
DISPLAY INVISIBLE (4700 4700);
FORCEPROP 2 LAST CDS_LIB pure_quanta
J 0
(4650 4525);
PAINT MONO (4650 4525);
DISPLAY INVISIBLE (4650 4525);
FORCEPROP 2 LAST CDS_LOCATION R4140
J 0
(4700 4750);
DISPLAY 1.021277 (4700 4750);
DISPLAY INVISIBLE (4700 4750);
FORCEPROP 2 LAST $SEC 1
J 0
(4700 4750);
DISPLAY 0.680851 (4700 4750);
PAINT MONO (4700 4750);
DISPLAY INVISIBLE (4700 4750);
FORCEPROP 2 LAST CDS_SEC 1
J 0
(4700 4750);
DISPLAY 1.021277 (4700 4750);
DISPLAY INVISIBLE (4700 4750);
FORCEADD OFFPAGE..2
(5775 4350);
FORCEPROP 2 LAST $XR0 215 
J 0
(5964 4350);
DISPLAY 0.638298 (5964 4350);
PAINT MONO (5964 4350);
FORCEPROP 1 LAST OFFPAGE TRUE
J 0
(6100 4225);
DISPLAY 0.872340 (6100 4225);
PAINT AQUA (6100 4225);
DISPLAY INVISIBLE (6100 4225);
FORCEPROP 1 LAST COMMENT_BODY TRUE
J 0
(5730 4255);
DISPLAY 0.872340 (5730 4255);
PAINT GREEN (5730 4255);
DISPLAY INVISIBLE (5730 4255);
FORCEPROP 2 LAST CDS_LIB standard
J 0
(5775 4350);
DISPLAY INVISIBLE (5775 4350);
FORCEPROP 2 LAST PATH I53
J 0
(5975 4400);
DISPLAY 1.021277 (5975 4400);
DISPLAY INVISIBLE (5975 4400);
FORCEADD OFFPAGE..2
(5800 2975);
FORCEPROP 2 LAST $XR1 227 
J 0
(6109 2975);
DISPLAY 0.638298 (6109 2975);
PAINT MONO (6109 2975);
FORCEPROP 2 LAST $XR0 215 
J 0
(5989 2975);
DISPLAY 0.638298 (5989 2975);
PAINT MONO (5989 2975);
FORCEPROP 1 LAST OFFPAGE TRUE
J 0
(6125 2850);
DISPLAY 0.872340 (6125 2850);
PAINT AQUA (6125 2850);
DISPLAY INVISIBLE (6125 2850);
FORCEPROP 1 LAST COMMENT_BODY TRUE
J 0
(5755 2880);
DISPLAY 0.872340 (5755 2880);
PAINT GREEN (5755 2880);
DISPLAY INVISIBLE (5755 2880);
FORCEPROP 2 LAST CDS_LIB standard
J 0
(5800 2975);
DISPLAY INVISIBLE (5800 2975);
FORCEPROP 2 LAST PATH I54
J 0
(6000 3025);
DISPLAY 1.021277 (6000 3025);
DISPLAY INVISIBLE (6000 3025);
FORCEADD Q_CAP..1
(5425 4050);
FORCEPROP 1 LAST PART_NUMBER TMP_QCH21006JB10
J 0
(5475 3900);
DISPLAY 0.638298 (5475 3900);
DISPLAY INVISIBLE (5475 3900);
FORCEPROP 1 LAST MATERIAL EMPTY
J 0
(5475 3950);
DISPLAY 0.638298 (5475 3950);
PAINT RED (5475 3950);
FORCEPROP 1 LAST TOLERANCE 5%
J 0
(5475 4000);
DISPLAY 0.638298 (5475 4000);
FORCEPROP 1 LAST VOLTAGE 50V
J 0
(5475 4050);
DISPLAY 0.638298 (5475 4050);
FORCEPROP 1 LAST VALUE 1000PF
J 0
(5475 4100);
DISPLAY 0.638298 (5475 4100);
FORCEPROP 1 LAST PACK_TYPE 0402
J 0
(5475 3850);
DISPLAY 0.638298 (5475 3850);
FORCEPROP 1 LAST $LOCATION C2267
J 0
(5475 4150);
DISPLAY 0.978723 (5475 4150);
FORCEPROP 1 LASTPIN (5425 4150) $PN 1
J 0
(5435 4130);
DISPLAY 0.787234 (5435 4130);
PAINT MONO (5435 4130);
FORCEPROP 1 LASTPIN (5425 3950) $PN 2
J 0
(5435 3930);
DISPLAY 0.787234 (5435 3930);
PAINT MONO (5435 3930);
FORCEPROP 2 LAST CDS_LIB pure_quanta
J 0
(5425 4050);
DISPLAY INVISIBLE (5425 4050);
FORCEPROP 1 LAST PATH I55
J 0
(5475 4200);
DISPLAY 0.978723 (5475 4200);
PAINT WHITE (5475 4200);
DISPLAY INVISIBLE (5475 4200);
FORCEPROP 0 LAST CDS_LOCATION C2267
J 0
(5475 4200);
DISPLAY 1.021277 (5475 4200);
DISPLAY INVISIBLE (5475 4200);
FORCEPROP 0 LAST $SEC 1
J 0
(5475 4200);
DISPLAY 0.680851 (5475 4200);
PAINT MONO (5475 4200);
DISPLAY INVISIBLE (5475 4200);
FORCEPROP 0 LAST CDS_SEC 1
J 0
(5475 4200);
DISPLAY 1.021277 (5475 4200);
DISPLAY INVISIBLE (5475 4200);
FORCEADD UNIVERSAL_GND..1
(5425 3850);
FORCEPROP 3 LASTPIN (5425 3900) SIG_NAME GND\g
J 0
(5435 3910);
DISPLAY 0.659574 (5435 3910);
PAINT MONO (5435 3910);
DISPLAY INVISIBLE (5435 3910);
FORCEPROP 1 LAST HDL_POWER GND
J 1
(5450 3775);
DISPLAY 0.872340 (5450 3775);
PAINT GREEN (5450 3775);
DISPLAY INVISIBLE (5450 3775);
FORCEPROP 2 LAST CDS_LIB logical_power
J 0
(5425 3850);
DISPLAY INVISIBLE (5425 3850);
FORCEPROP 1 LAST PATH I56
J 0
(5500 3850);
DISPLAY 0.872340 (5500 3850);
PAINT AQUA (5500 3850);
DISPLAY INVISIBLE (5500 3850);
FORCEADD Q_CAP..1
(5450 2675);
FORCEPROP 1 LAST PART_NUMBER TMP_QCH21006JB10
J 0
(5500 2525);
DISPLAY 0.638298 (5500 2525);
DISPLAY INVISIBLE (5500 2525);
FORCEPROP 1 LAST MATERIAL EMPTY
J 0
(5500 2575);
DISPLAY 0.638298 (5500 2575);
PAINT RED (5500 2575);
FORCEPROP 1 LAST TOLERANCE 5%
J 0
(5500 2625);
DISPLAY 0.638298 (5500 2625);
FORCEPROP 1 LAST VOLTAGE 50V
J 0
(5500 2675);
DISPLAY 0.638298 (5500 2675);
FORCEPROP 1 LAST VALUE 1000PF
J 0
(5500 2725);
DISPLAY 0.638298 (5500 2725);
FORCEPROP 1 LAST PACK_TYPE 0402
J 0
(5500 2475);
DISPLAY 0.638298 (5500 2475);
FORCEPROP 1 LAST $LOCATION C2269
J 0
(5500 2775);
DISPLAY 0.978723 (5500 2775);
FORCEPROP 1 LASTPIN (5450 2775) $PN 1
J 0
(5460 2755);
DISPLAY 0.787234 (5460 2755);
PAINT MONO (5460 2755);
FORCEPROP 1 LASTPIN (5450 2575) $PN 2
J 0
(5460 2555);
DISPLAY 0.787234 (5460 2555);
PAINT MONO (5460 2555);
FORCEPROP 2 LAST CDS_LIB pure_quanta
J 0
(5450 2675);
DISPLAY INVISIBLE (5450 2675);
FORCEPROP 1 LAST PATH I57
J 0
(5500 2825);
DISPLAY 0.978723 (5500 2825);
PAINT WHITE (5500 2825);
DISPLAY INVISIBLE (5500 2825);
FORCEPROP 0 LAST CDS_LOCATION C2269
J 0
(5500 2825);
DISPLAY 1.021277 (5500 2825);
DISPLAY INVISIBLE (5500 2825);
FORCEPROP 0 LAST $SEC 1
J 0
(5500 2825);
DISPLAY 0.680851 (5500 2825);
PAINT MONO (5500 2825);
DISPLAY INVISIBLE (5500 2825);
FORCEPROP 0 LAST CDS_SEC 1
J 0
(5500 2825);
DISPLAY 1.021277 (5500 2825);
DISPLAY INVISIBLE (5500 2825);
FORCEADD UNIVERSAL_GND..1
(5450 2475);
FORCEPROP 3 LASTPIN (5450 2525) SIG_NAME GND\g
J 0
(5460 2535);
DISPLAY 0.659574 (5460 2535);
PAINT MONO (5460 2535);
DISPLAY INVISIBLE (5460 2535);
FORCEPROP 1 LAST HDL_POWER GND
J 1
(5475 2400);
DISPLAY 0.872340 (5475 2400);
PAINT GREEN (5475 2400);
DISPLAY INVISIBLE (5475 2400);
FORCEPROP 2 LAST CDS_LIB logical_power
J 0
(5450 2475);
DISPLAY INVISIBLE (5450 2475);
FORCEPROP 1 LAST PATH I58
J 0
(5525 2475);
DISPLAY 0.872340 (5525 2475);
PAINT AQUA (5525 2475);
DISPLAY INVISIBLE (5525 2475);
FORCEADD UNIVERSAL_POWER..1
(4675 3375);
FORCEPROP 3 LASTPIN (4675 3325) SIG_NAME P3V3_AUX\g
J 0
(4685 3335);
DISPLAY 0.659574 (4685 3335);
PAINT MONO (4685 3335);
DISPLAY INVISIBLE (4685 3335);
FORCEPROP 1 LAST HDL_POWER P3V3_AUX
J 1
(4675 3425);
DISPLAY 0.872340 (4675 3425);
PAINT GREEN (4675 3425);
FORCEPROP 2 LAST CDS_LIB logical_power
J 0
(4675 3375);
PAINT MONO (4675 3375);
DISPLAY INVISIBLE (4675 3375);
FORCEPROP 1 LAST PATH I59
J 0
(4725 3400);
DISPLAY 0.872340 (4725 3400);
PAINT AQUA (4725 3400);
DISPLAY INVISIBLE (4725 3400);
FORCEADD MOSFET_NCH_DUAL..2
(-25 3800);
FORCEPROP 1 LAST PART_NUMBER BAM138K0003
J 0
(126 3706);
DISPLAY 0.723404 (126 3706);
PAINT GREEN (126 3706);
DISPLAY INVISIBLE (126 3706);
FORCEPROP 2 LAST PART_TYPE SMLF
J 0
(150 3875);
DISPLAY 1.021277 (150 3875);
FORCEPROP 2 LAST VALUE PJT138K
J 0
(150 3825);
DISPLAY 1.021277 (150 3825);
FORCEPROP 1 LAST MATERIAL IC
J 0
(126 3651);
DISPLAY 0.723404 (126 3651);
PAINT GREEN (126 3651);
FORCEPROP 1 LAST LOCATION Q128
J 0
(126 3776);
DISPLAY 0.723404 (126 3776);
PAINT GREEN (126 3776);
FORCEPROP 0 LASTPIN (25 4000) $PN 3
R 1
J 0
(15 4010);
DISPLAY 0.680851 (15 4010);
PAINT MONO (15 4010);
FORCEPROP 0 LASTPIN (-225 3750) $PN 5
J 2
(-235 3760);
DISPLAY 0.680851 (-235 3760);
PAINT MONO (-235 3760);
FORCEPROP 0 LASTPIN (25 3600) $PN 4
R 1
J 2
(15 3590);
DISPLAY 0.680851 (15 3590);
PAINT MONO (15 3590);
FORCEPROP 1 LAST CDS_LMAN_SYM_OUTLINE -150,150,150,-150
J 0
(-25 3800);
DISPLAY 0.468085 (-25 3800);
PAINT GREEN (-25 3800);
DISPLAY INVISIBLE (-25 3800);
FORCEPROP 1 LAST NEEDS_NO_SIZE TRUE
J 0
(125 3691);
DISPLAY 0.468085 (125 3691);
PAINT GREEN (125 3691);
DISPLAY INVISIBLE (125 3691);
FORCEPROP 2 LAST CDS_LIB pure_quanta
J 0
(-25 3800);
DISPLAY INVISIBLE (-25 3800);
FORCEPROP 1 LAST PATH I6
J 0
(125 3650);
DISPLAY 0.723404 (125 3650);
PAINT GREEN (125 3650);
DISPLAY INVISIBLE (125 3650);
FORCEPROP 0 LAST $SEC 2
J 0
(150 3925);
DISPLAY 0.680851 (150 3925);
PAINT MONO (150 3925);
DISPLAY INVISIBLE (150 3925);
FORCEPROP 0 LAST CDS_SEC 2
J 0
(150 3925);
DISPLAY 1.021277 (150 3925);
DISPLAY INVISIBLE (150 3925);
FORCEADD Q_RES..2
(4675 3150);
FORCEPROP 1 LAST PART_NUMBER CS24702JB10
J 0
(4715 2975);
DISPLAY 0.638298 (4715 2975);
DISPLAY INVISIBLE (4715 2975);
FORCEPROP 1 LAST PACK_TYPE 0402LF
J 0
(4715 3025);
DISPLAY 0.638298 (4715 3025);
FORCEPROP 1 LAST VALUE 4.7K
J 0
(4720 3225);
DISPLAY 0.638298 (4720 3225);
FORCEPROP 1 LAST TOLERANCE 5%
J 0
(4720 3175);
DISPLAY 0.638298 (4720 3175);
FORCEPROP 1 LAST WATTAGE 1/16W
J 0
(4715 3125);
DISPLAY 0.638298 (4715 3125);
FORCEPROP 1 LAST MATERIAL CHIP
J 0
(4715 3075);
DISPLAY 0.638298 (4715 3075);
FORCEPROP 1 LAST $LOCATION R4142
J 0
(4720 3275);
DISPLAY 0.638298 (4720 3275);
FORCEPROP 1 LASTPIN (4675 3250) $PN 1
J 0
(4680 3212);
DISPLAY 0.787234 (4680 3212);
FORCEPROP 1 LASTPIN (4675 3050) $PN 2
J 0
(4680 3060);
DISPLAY 0.787234 (4680 3060);
FORCEPROP 1 LAST PATH I60
J 0
(4725 3325);
DISPLAY 0.978723 (4725 3325);
PAINT WHITE (4725 3325);
DISPLAY INVISIBLE (4725 3325);
FORCEPROP 2 LAST CDS_LIB pure_quanta
J 0
(4675 3150);
PAINT MONO (4675 3150);
DISPLAY INVISIBLE (4675 3150);
FORCEPROP 2 LAST CDS_LOCATION R4142
J 0
(4725 3375);
DISPLAY 1.021277 (4725 3375);
DISPLAY INVISIBLE (4725 3375);
FORCEPROP 2 LAST $SEC 1
J 0
(4725 3375);
DISPLAY 0.680851 (4725 3375);
PAINT MONO (4725 3375);
DISPLAY INVISIBLE (4725 3375);
FORCEPROP 2 LAST CDS_SEC 1
J 0
(4725 3375);
DISPLAY 1.021277 (4725 3375);
DISPLAY INVISIBLE (4725 3375);
FORCEADD OFFPAGE..2
(5775 1525);
FORCEPROP 2 LAST $XR0 215 
J 0
(5964 1525);
DISPLAY 0.638298 (5964 1525);
PAINT MONO (5964 1525);
FORCEPROP 2 LAST PATH I61
J 0
(5975 1575);
DISPLAY 1.021277 (5975 1575);
DISPLAY INVISIBLE (5975 1575);
FORCEPROP 2 LAST CDS_LIB standard
J 0
(5775 1525);
DISPLAY INVISIBLE (5775 1525);
FORCEPROP 1 LAST COMMENT_BODY TRUE
J 0
(5730 1430);
DISPLAY 0.872340 (5730 1430);
PAINT GREEN (5730 1430);
DISPLAY INVISIBLE (5730 1430);
FORCEPROP 1 LAST OFFPAGE TRUE
J 0
(6100 1400);
DISPLAY 0.872340 (6100 1400);
PAINT AQUA (6100 1400);
DISPLAY INVISIBLE (6100 1400);
FORCEADD UNIVERSAL_POWER..1
(4650 1925);
FORCEPROP 3 LASTPIN (4650 1875) SIG_NAME P3V3_AUX\g
J 0
(4660 1885);
DISPLAY 0.659574 (4660 1885);
PAINT MONO (4660 1885);
DISPLAY INVISIBLE (4660 1885);
FORCEPROP 1 LAST HDL_POWER P3V3_AUX
J 1
(4650 1975);
DISPLAY 0.872340 (4650 1975);
PAINT GREEN (4650 1975);
FORCEPROP 1 LAST PATH I62
J 0
(4700 1950);
DISPLAY 0.872340 (4700 1950);
PAINT AQUA (4700 1950);
DISPLAY INVISIBLE (4700 1950);
FORCEPROP 2 LAST CDS_LIB logical_power
J 0
(4650 1925);
PAINT MONO (4650 1925);
DISPLAY INVISIBLE (4650 1925);
FORCEADD UNIVERSAL_GND..1
(4675 2350);
FORCEPROP 3 LASTPIN (4675 2400) SIG_NAME GND\g
J 0
(4685 2410);
DISPLAY 0.659574 (4685 2410);
PAINT MONO (4685 2410);
DISPLAY INVISIBLE (4685 2410);
FORCEPROP 1 LAST HDL_POWER GND
J 1
(4700 2275);
DISPLAY 0.872340 (4700 2275);
PAINT GREEN (4700 2275);
DISPLAY INVISIBLE (4700 2275);
FORCEPROP 2 LAST CDS_LIB logical_power
J 0
(4675 2350);
DISPLAY INVISIBLE (4675 2350);
FORCEPROP 1 LAST PATH I63
J 0
(4750 2350);
DISPLAY 0.872340 (4750 2350);
PAINT AQUA (4750 2350);
DISPLAY INVISIBLE (4750 2350);
FORCEADD Q_RES..2
(4650 1700);
FORCEPROP 1 LAST PART_NUMBER CS24702JB10
J 0
(4690 1525);
DISPLAY 0.638298 (4690 1525);
DISPLAY INVISIBLE (4690 1525);
FORCEPROP 1 LAST MATERIAL CHIP
J 0
(4690 1625);
DISPLAY 0.638298 (4690 1625);
FORCEPROP 1 LAST WATTAGE 1/16W
J 0
(4690 1675);
DISPLAY 0.638298 (4690 1675);
FORCEPROP 1 LAST PACK_TYPE 0402LF
J 0
(4690 1575);
DISPLAY 0.638298 (4690 1575);
FORCEPROP 1 LAST TOLERANCE 5%
J 0
(4695 1725);
DISPLAY 0.638298 (4695 1725);
FORCEPROP 1 LAST VALUE 4.7K
J 0
(4695 1775);
DISPLAY 0.638298 (4695 1775);
FORCEPROP 1 LAST $LOCATION R4141
J 0
(4695 1825);
DISPLAY 0.638298 (4695 1825);
FORCEPROP 1 LASTPIN (4650 1800) $PN 1
J 0
(4655 1762);
DISPLAY 0.787234 (4655 1762);
FORCEPROP 1 LASTPIN (4650 1600) $PN 2
J 0
(4655 1610);
DISPLAY 0.787234 (4655 1610);
FORCEPROP 1 LAST PATH I64
J 0
(4700 1875);
DISPLAY 0.978723 (4700 1875);
PAINT WHITE (4700 1875);
DISPLAY INVISIBLE (4700 1875);
FORCEPROP 2 LAST CDS_LIB pure_quanta
J 0
(4650 1700);
PAINT MONO (4650 1700);
DISPLAY INVISIBLE (4650 1700);
FORCEPROP 2 LAST CDS_LOCATION R4141
J 0
(4700 1925);
DISPLAY 1.021277 (4700 1925);
DISPLAY INVISIBLE (4700 1925);
FORCEPROP 2 LAST $SEC 1
J 0
(4700 1925);
DISPLAY 0.680851 (4700 1925);
PAINT MONO (4700 1925);
DISPLAY INVISIBLE (4700 1925);
FORCEPROP 2 LAST CDS_SEC 1
J 0
(4700 1925);
DISPLAY 1.021277 (4700 1925);
DISPLAY INVISIBLE (4700 1925);
FORCEADD UNIVERSAL_GND..1
(5425 1025);
FORCEPROP 3 LASTPIN (5425 1075) SIG_NAME GND\g
J 0
(5435 1085);
DISPLAY 0.659574 (5435 1085);
PAINT MONO (5435 1085);
DISPLAY INVISIBLE (5435 1085);
FORCEPROP 1 LAST PATH I65
J 0
(5500 1025);
DISPLAY 0.872340 (5500 1025);
PAINT AQUA (5500 1025);
DISPLAY INVISIBLE (5500 1025);
FORCEPROP 2 LAST CDS_LIB logical_power
J 0
(5425 1025);
DISPLAY INVISIBLE (5425 1025);
FORCEPROP 1 LAST HDL_POWER GND
J 1
(5450 950);
DISPLAY 0.872340 (5450 950);
PAINT GREEN (5450 950);
DISPLAY INVISIBLE (5450 950);
FORCEADD Q_CAP..1
(5425 1225);
FORCEPROP 1 LAST PART_NUMBER TMP_QCH21006JB10
J 0
(5475 1075);
DISPLAY 0.638298 (5475 1075);
DISPLAY INVISIBLE (5475 1075);
FORCEPROP 1 LAST VOLTAGE 50V
J 0
(5475 1225);
DISPLAY 0.638298 (5475 1225);
FORCEPROP 1 LAST TOLERANCE 5%
J 0
(5475 1175);
DISPLAY 0.638298 (5475 1175);
FORCEPROP 1 LAST PACK_TYPE 0402
J 0
(5475 1025);
DISPLAY 0.638298 (5475 1025);
FORCEPROP 1 LAST VALUE 1000PF
J 0
(5475 1275);
DISPLAY 0.638298 (5475 1275);
FORCEPROP 1 LAST MATERIAL EMPTY
J 0
(5475 1125);
DISPLAY 0.638298 (5475 1125);
PAINT RED (5475 1125);
FORCEPROP 1 LAST $LOCATION C2268
J 0
(5475 1325);
DISPLAY 0.978723 (5475 1325);
FORCEPROP 1 LASTPIN (5425 1325) $PN 1
J 0
(5435 1305);
DISPLAY 0.787234 (5435 1305);
PAINT MONO (5435 1305);
FORCEPROP 1 LASTPIN (5425 1125) $PN 2
J 0
(5435 1105);
DISPLAY 0.787234 (5435 1105);
PAINT MONO (5435 1105);
FORCEPROP 1 LAST PATH I66
J 0
(5475 1375);
DISPLAY 0.978723 (5475 1375);
PAINT WHITE (5475 1375);
DISPLAY INVISIBLE (5475 1375);
FORCEPROP 2 LAST CDS_LIB pure_quanta
J 0
(5425 1225);
DISPLAY INVISIBLE (5425 1225);
FORCEPROP 0 LAST CDS_LOCATION C2268
J 0
(5475 1375);
DISPLAY 1.021277 (5475 1375);
DISPLAY INVISIBLE (5475 1375);
FORCEPROP 0 LAST $SEC 1
J 0
(5475 1375);
DISPLAY 0.680851 (5475 1375);
PAINT MONO (5475 1375);
DISPLAY INVISIBLE (5475 1375);
FORCEPROP 0 LAST CDS_SEC 1
J 0
(5475 1375);
DISPLAY 1.021277 (5475 1375);
DISPLAY INVISIBLE (5475 1375);
FORCEADD UNIVERSAL_GND..1
(4650 900);
FORCEPROP 3 LASTPIN (4650 950) SIG_NAME GND\g
J 0
(4660 960);
DISPLAY 0.659574 (4660 960);
PAINT MONO (4660 960);
DISPLAY INVISIBLE (4660 960);
FORCEPROP 1 LAST PATH I67
J 0
(4725 900);
DISPLAY 0.872340 (4725 900);
PAINT AQUA (4725 900);
DISPLAY INVISIBLE (4725 900);
FORCEPROP 2 LAST CDS_LIB logical_power
J 0
(4650 900);
DISPLAY INVISIBLE (4650 900);
FORCEPROP 1 LAST HDL_POWER GND
J 1
(4675 825);
DISPLAY 0.872340 (4675 825);
PAINT GREEN (4675 825);
DISPLAY INVISIBLE (4675 825);
FORCEADD UNIVERSAL_GND..1
(4650 3725);
FORCEPROP 3 LASTPIN (4650 3775) SIG_NAME GND\g
J 0
(4660 3785);
DISPLAY 0.659574 (4660 3785);
PAINT MONO (4660 3785);
DISPLAY INVISIBLE (4660 3785);
FORCEPROP 1 LAST HDL_POWER GND
J 1
(4675 3650);
DISPLAY 0.872340 (4675 3650);
PAINT GREEN (4675 3650);
DISPLAY INVISIBLE (4675 3650);
FORCEPROP 2 LAST CDS_LIB logical_power
J 0
(4650 3725);
DISPLAY INVISIBLE (4650 3725);
FORCEPROP 1 LAST PATH I68
J 0
(4725 3725);
DISPLAY 0.872340 (4725 3725);
PAINT AQUA (4725 3725);
DISPLAY INVISIBLE (4725 3725);
FORCEADD UNIVERSAL_POWER..1
(3500 4625);
FORCEPROP 3 LASTPIN (3500 4575) SIG_NAME P3V3_AUX\g
J 0
(3510 4585);
DISPLAY 0.659574 (3510 4585);
PAINT MONO (3510 4585);
DISPLAY INVISIBLE (3510 4585);
FORCEPROP 1 LAST HDL_POWER P3V3_AUX
J 1
(3500 4675);
DISPLAY 0.872340 (3500 4675);
PAINT GREEN (3500 4675);
FORCEPROP 2 LAST CDS_LIB logical_power
J 0
(3500 4625);
PAINT MONO (3500 4625);
DISPLAY INVISIBLE (3500 4625);
FORCEPROP 1 LAST PATH I69
J 0
(3550 4650);
DISPLAY 0.872340 (3550 4650);
PAINT AQUA (3550 4650);
DISPLAY INVISIBLE (3550 4650);
FORCEADD UNIVERSAL_GND..1
(25 3425);
FORCEPROP 3 LASTPIN (25 3475) SIG_NAME GND\g
J 0
(35 3485);
DISPLAY 0.659574 (35 3485);
PAINT MONO (35 3485);
DISPLAY INVISIBLE (35 3485);
FORCEPROP 1 LAST PATH I7
J 0
(100 3425);
DISPLAY 0.872340 (100 3425);
PAINT AQUA (100 3425);
DISPLAY INVISIBLE (100 3425);
FORCEPROP 2 LAST CDS_LIB logical_power
J 0
(25 3425);
DISPLAY INVISIBLE (25 3425);
FORCEPROP 1 LAST HDL_POWER GND
J 1
(50 3350);
DISPLAY 0.872340 (50 3350);
PAINT GREEN (50 3350);
DISPLAY INVISIBLE (50 3350);
FORCEADD MOSFET_NCH_DUAL..2
(4600 4100);
FORCEPROP 1 LAST PART_NUMBER BAM138K0003
J 0
(4751 4006);
DISPLAY 0.723404 (4751 4006);
PAINT GREEN (4751 4006);
DISPLAY INVISIBLE (4751 4006);
FORCEPROP 2 LAST PART_TYPE SMLF
J 0
(4775 4175);
DISPLAY 1.021277 (4775 4175);
FORCEPROP 2 LAST VALUE PJT138K
J 0
(4775 4125);
DISPLAY 1.021277 (4775 4125);
FORCEPROP 1 LAST MATERIAL IC
J 0
(4751 3951);
DISPLAY 0.723404 (4751 3951);
PAINT GREEN (4751 3951);
FORCEPROP 1 LAST $LOCATION Q130
J 0
(4751 4076);
DISPLAY 0.723404 (4751 4076);
PAINT GREEN (4751 4076);
FORCEPROP 0 LASTPIN (4650 4300) $PN 3
R 1
J 0
(4640 4310);
DISPLAY 0.680851 (4640 4310);
PAINT MONO (4640 4310);
FORCEPROP 0 LASTPIN (4400 4050) $PN 5
J 2
(4390 4060);
DISPLAY 0.680851 (4390 4060);
PAINT MONO (4390 4060);
FORCEPROP 0 LASTPIN (4650 3900) $PN 4
R 1
J 2
(4640 3890);
DISPLAY 0.680851 (4640 3890);
PAINT MONO (4640 3890);
FORCEPROP 1 LAST CDS_LMAN_SYM_OUTLINE -150,150,150,-150
J 0
(4600 4100);
DISPLAY 0.468085 (4600 4100);
PAINT GREEN (4600 4100);
DISPLAY INVISIBLE (4600 4100);
FORCEPROP 1 LAST NEEDS_NO_SIZE TRUE
J 0
(4750 3991);
DISPLAY 0.468085 (4750 3991);
PAINT GREEN (4750 3991);
DISPLAY INVISIBLE (4750 3991);
FORCEPROP 2 LAST CDS_LIB pure_quanta
J 0
(4600 4100);
DISPLAY INVISIBLE (4600 4100);
FORCEPROP 1 LAST PATH I70
J 0
(4750 3950);
DISPLAY 0.723404 (4750 3950);
PAINT GREEN (4750 3950);
DISPLAY INVISIBLE (4750 3950);
FORCEPROP 0 LAST CDS_LOCATION Q130
J 0
(4775 4225);
DISPLAY 1.021277 (4775 4225);
DISPLAY INVISIBLE (4775 4225);
FORCEPROP 0 LAST $SEC 2
J 0
(4775 4225);
DISPLAY 0.680851 (4775 4225);
PAINT MONO (4775 4225);
DISPLAY INVISIBLE (4775 4225);
FORCEPROP 0 LAST CDS_SEC 2
J 0
(4775 4225);
DISPLAY 1.021277 (4775 4225);
DISPLAY INVISIBLE (4775 4225);
FORCEADD MOSFET_NCH_DUAL..2
(4625 2725);
FORCEPROP 1 LAST PART_NUMBER BAM138K0003
J 0
(4776 2631);
DISPLAY 0.723404 (4776 2631);
PAINT GREEN (4776 2631);
DISPLAY INVISIBLE (4776 2631);
FORCEPROP 2 LAST VALUE PJT138K
J 0
(4800 2750);
DISPLAY 1.021277 (4800 2750);
FORCEPROP 2 LAST PART_TYPE SMLF
J 0
(4800 2800);
DISPLAY 1.021277 (4800 2800);
FORCEPROP 1 LAST MATERIAL IC
J 0
(4776 2576);
DISPLAY 0.723404 (4776 2576);
PAINT GREEN (4776 2576);
FORCEPROP 1 LAST LOCATION Q133
J 0
(4776 2701);
DISPLAY 0.723404 (4776 2701);
PAINT GREEN (4776 2701);
FORCEPROP 0 LASTPIN (4675 2925) $PN 3
R 1
J 0
(4665 2935);
DISPLAY 0.680851 (4665 2935);
PAINT MONO (4665 2935);
FORCEPROP 0 LASTPIN (4425 2675) $PN 5
J 2
(4415 2685);
DISPLAY 0.680851 (4415 2685);
PAINT MONO (4415 2685);
FORCEPROP 0 LASTPIN (4675 2525) $PN 4
R 1
J 2
(4665 2515);
DISPLAY 0.680851 (4665 2515);
PAINT MONO (4665 2515);
FORCEPROP 1 LAST PATH I71
J 0
(4775 2575);
DISPLAY 0.723404 (4775 2575);
PAINT GREEN (4775 2575);
DISPLAY INVISIBLE (4775 2575);
FORCEPROP 2 LAST CDS_LIB pure_quanta
J 0
(4625 2725);
DISPLAY INVISIBLE (4625 2725);
FORCEPROP 1 LAST NEEDS_NO_SIZE TRUE
J 0
(4775 2616);
DISPLAY 0.468085 (4775 2616);
PAINT GREEN (4775 2616);
DISPLAY INVISIBLE (4775 2616);
FORCEPROP 1 LAST CDS_LMAN_SYM_OUTLINE -150,150,150,-150
J 0
(4625 2725);
DISPLAY 0.468085 (4625 2725);
PAINT GREEN (4625 2725);
DISPLAY INVISIBLE (4625 2725);
FORCEPROP 0 LAST $SEC 2
J 0
(4800 2850);
DISPLAY 0.680851 (4800 2850);
PAINT MONO (4800 2850);
DISPLAY INVISIBLE (4800 2850);
FORCEPROP 0 LAST CDS_SEC 2
J 0
(4800 2850);
DISPLAY 1.021277 (4800 2850);
DISPLAY INVISIBLE (4800 2850);
FORCEADD Q_RES..2
(3500 4400);
FORCEPROP 1 LAST PART_NUMBER CS24702JB10
J 0
(3540 4225);
DISPLAY 0.638298 (3540 4225);
DISPLAY INVISIBLE (3540 4225);
FORCEPROP 1 LAST TOLERANCE 5%
J 0
(3545 4425);
DISPLAY 0.638298 (3545 4425);
FORCEPROP 1 LAST VALUE 4.7K
J 0
(3545 4475);
DISPLAY 0.638298 (3545 4475);
FORCEPROP 1 LAST WATTAGE 1/16W
J 0
(3540 4375);
DISPLAY 0.638298 (3540 4375);
FORCEPROP 1 LAST PACK_TYPE 0402LF
J 0
(3540 4275);
DISPLAY 0.638298 (3540 4275);
FORCEPROP 1 LAST MATERIAL CHIP
J 0
(3540 4325);
DISPLAY 0.638298 (3540 4325);
FORCEPROP 1 LAST $LOCATION R4137
J 0
(3545 4525);
DISPLAY 0.638298 (3545 4525);
FORCEPROP 1 LASTPIN (3500 4500) $PN 1
J 0
(3505 4462);
DISPLAY 0.787234 (3505 4462);
FORCEPROP 1 LASTPIN (3500 4300) $PN 2
J 0
(3505 4310);
DISPLAY 0.787234 (3505 4310);
FORCEPROP 1 LAST PATH I72
J 0
(3550 4575);
DISPLAY 0.978723 (3550 4575);
PAINT WHITE (3550 4575);
DISPLAY INVISIBLE (3550 4575);
FORCEPROP 2 LAST CDS_LIB pure_quanta
J 0
(3500 4400);
PAINT MONO (3500 4400);
DISPLAY INVISIBLE (3500 4400);
FORCEPROP 2 LAST CDS_LOCATION R4137
J 0
(3550 4625);
DISPLAY 1.021277 (3550 4625);
DISPLAY INVISIBLE (3550 4625);
FORCEPROP 2 LAST $SEC 1
J 0
(3550 4625);
DISPLAY 0.680851 (3550 4625);
PAINT MONO (3550 4625);
DISPLAY INVISIBLE (3550 4625);
FORCEPROP 2 LAST CDS_SEC 1
J 0
(3550 4625);
DISPLAY 1.021277 (3550 4625);
DISPLAY INVISIBLE (3550 4625);
FORCEADD UNIVERSAL_GND..1
(3500 3425);
FORCEPROP 3 LASTPIN (3500 3475) SIG_NAME GND\g
J 0
(3510 3485);
DISPLAY 0.659574 (3510 3485);
PAINT MONO (3510 3485);
DISPLAY INVISIBLE (3510 3485);
FORCEPROP 1 LAST HDL_POWER GND
J 1
(3525 3350);
DISPLAY 0.872340 (3525 3350);
PAINT GREEN (3525 3350);
DISPLAY INVISIBLE (3525 3350);
FORCEPROP 2 LAST CDS_LIB logical_power
J 0
(3500 3425);
DISPLAY INVISIBLE (3500 3425);
FORCEPROP 1 LAST PATH I73
J 0
(3575 3425);
DISPLAY 0.872340 (3575 3425);
PAINT AQUA (3575 3425);
DISPLAY INVISIBLE (3575 3425);
FORCEADD MOSFET_NCH_DUAL..1
(3450 3800);
FORCEPROP 1 LAST PART_NUMBER BAM138K0003
J 0
(3601 3714);
DISPLAY 0.723404 (3601 3714);
PAINT GREEN (3601 3714);
DISPLAY INVISIBLE (3601 3714);
FORCEPROP 1 LAST MATERIAL IC
J 0
(3601 3649);
DISPLAY 0.723404 (3601 3649);
PAINT GREEN (3601 3649);
FORCEPROP 2 LAST PART_TYPE SMLF
J 0
(3625 3875);
DISPLAY 1.021277 (3625 3875);
FORCEPROP 2 LAST VALUE PJT138K
J 0
(3625 3825);
DISPLAY 1.021277 (3625 3825);
FORCEPROP 1 LAST LOCATION Q130
J 0
(3601 3774);
DISPLAY 0.723404 (3601 3774);
PAINT GREEN (3601 3774);
FORCEPROP 0 LASTPIN (3500 4000) $PN 6
R 1
J 0
(3490 4010);
DISPLAY 0.680851 (3490 4010);
PAINT MONO (3490 4010);
FORCEPROP 0 LASTPIN (3250 3750) $PN 2
J 2
(3240 3760);
DISPLAY 0.680851 (3240 3760);
PAINT MONO (3240 3760);
FORCEPROP 0 LASTPIN (3500 3600) $PN 1
R 1
J 2
(3490 3590);
DISPLAY 0.680851 (3490 3590);
PAINT MONO (3490 3590);
FORCEPROP 1 LAST PATH I74
J 0
(3450 3800);
DISPLAY 0.723404 (3450 3800);
PAINT GREEN (3450 3800);
DISPLAY INVISIBLE (3450 3800);
FORCEPROP 1 LAST CDS_LMAN_SYM_OUTLINE -150,150,150,-150
J 0
(3450 3800);
DISPLAY 0.468085 (3450 3800);
PAINT GREEN (3450 3800);
DISPLAY INVISIBLE (3450 3800);
FORCEPROP 1 LAST NEEDS_NO_SIZE TRUE
J 0
(3450 3799);
DISPLAY 0.468085 (3450 3799);
PAINT GREEN (3450 3799);
DISPLAY INVISIBLE (3450 3799);
FORCEPROP 2 LAST CDS_LIB pure_quanta
J 0
(3450 3800);
DISPLAY INVISIBLE (3450 3800);
FORCEPROP 0 LAST $SEC 1
J 0
(3625 3925);
DISPLAY 0.680851 (3625 3925);
PAINT MONO (3625 3925);
DISPLAY INVISIBLE (3625 3925);
FORCEPROP 2 LAST CDS_SEC 1
J 0
(3625 3925);
DISPLAY 1.021277 (3625 3925);
DISPLAY INVISIBLE (3625 3925);
FORCEADD UNIVERSAL_POWER..1
(3525 3250);
FORCEPROP 3 LASTPIN (3525 3200) SIG_NAME P3V3_AUX\g
J 0
(3535 3210);
DISPLAY 0.659574 (3535 3210);
PAINT MONO (3535 3210);
DISPLAY INVISIBLE (3535 3210);
FORCEPROP 1 LAST HDL_POWER P3V3_AUX
J 1
(3525 3300);
DISPLAY 0.872340 (3525 3300);
PAINT GREEN (3525 3300);
FORCEPROP 2 LAST CDS_LIB logical_power
J 0
(3525 3250);
PAINT MONO (3525 3250);
DISPLAY INVISIBLE (3525 3250);
FORCEPROP 1 LAST PATH I75
J 0
(3575 3275);
DISPLAY 0.872340 (3575 3275);
PAINT AQUA (3575 3275);
DISPLAY INVISIBLE (3575 3275);
FORCEADD Q_RES..2
(3525 3025);
FORCEPROP 1 LAST PART_NUMBER CS24702JB10
J 0
(3565 2850);
DISPLAY 0.638298 (3565 2850);
DISPLAY INVISIBLE (3565 2850);
FORCEPROP 1 LAST WATTAGE 1/16W
J 0
(3565 3000);
DISPLAY 0.638298 (3565 3000);
FORCEPROP 1 LAST TOLERANCE 5%
J 0
(3570 3050);
DISPLAY 0.638298 (3570 3050);
FORCEPROP 1 LAST PACK_TYPE 0402LF
J 0
(3565 2900);
DISPLAY 0.638298 (3565 2900);
FORCEPROP 1 LAST VALUE 4.7K
J 0
(3570 3100);
DISPLAY 0.638298 (3570 3100);
FORCEPROP 1 LAST MATERIAL CHIP
J 0
(3565 2950);
DISPLAY 0.638298 (3565 2950);
FORCEPROP 1 LAST $LOCATION R4139
J 0
(3570 3150);
DISPLAY 0.638298 (3570 3150);
FORCEPROP 1 LASTPIN (3525 3125) $PN 1
J 0
(3530 3087);
DISPLAY 0.787234 (3530 3087);
FORCEPROP 1 LASTPIN (3525 2925) $PN 2
J 0
(3530 2935);
DISPLAY 0.787234 (3530 2935);
FORCEPROP 1 LAST PATH I76
J 0
(3575 3200);
DISPLAY 0.978723 (3575 3200);
PAINT WHITE (3575 3200);
DISPLAY INVISIBLE (3575 3200);
FORCEPROP 2 LAST CDS_LIB pure_quanta
J 0
(3525 3025);
PAINT MONO (3525 3025);
DISPLAY INVISIBLE (3525 3025);
FORCEPROP 2 LAST CDS_LOCATION R4139
J 0
(3575 3250);
DISPLAY 1.021277 (3575 3250);
DISPLAY INVISIBLE (3575 3250);
FORCEPROP 2 LAST $SEC 1
J 0
(3575 3250);
DISPLAY 0.680851 (3575 3250);
PAINT MONO (3575 3250);
DISPLAY INVISIBLE (3575 3250);
FORCEPROP 2 LAST CDS_SEC 1
J 0
(3575 3250);
DISPLAY 1.021277 (3575 3250);
DISPLAY INVISIBLE (3575 3250);
FORCEADD MOSFET_NCH_DUAL..2
(4600 1275);
FORCEPROP 1 LAST PART_NUMBER BAM138K0003
J 0
(4751 1181);
DISPLAY 0.723404 (4751 1181);
PAINT GREEN (4751 1181);
DISPLAY INVISIBLE (4751 1181);
FORCEPROP 1 LAST MATERIAL IC
J 0
(4751 1126);
DISPLAY 0.723404 (4751 1126);
PAINT GREEN (4751 1126);
FORCEPROP 2 LAST PART_TYPE SMLF
J 0
(4775 1350);
DISPLAY 1.021277 (4775 1350);
FORCEPROP 2 LAST VALUE PJT138K
J 0
(4775 1300);
DISPLAY 1.021277 (4775 1300);
FORCEPROP 1 LAST $LOCATION Q129
J 0
(4751 1251);
DISPLAY 0.723404 (4751 1251);
PAINT GREEN (4751 1251);
FORCEPROP 0 LASTPIN (4650 1475) $PN 3
R 1
J 0
(4640 1485);
DISPLAY 0.680851 (4640 1485);
PAINT MONO (4640 1485);
FORCEPROP 0 LASTPIN (4400 1225) $PN 5
J 2
(4390 1235);
DISPLAY 0.680851 (4390 1235);
PAINT MONO (4390 1235);
FORCEPROP 0 LASTPIN (4650 1075) $PN 4
R 1
J 2
(4640 1065);
DISPLAY 0.680851 (4640 1065);
PAINT MONO (4640 1065);
FORCEPROP 1 LAST PATH I77
J 0
(4750 1125);
DISPLAY 0.723404 (4750 1125);
PAINT GREEN (4750 1125);
DISPLAY INVISIBLE (4750 1125);
FORCEPROP 1 LAST CDS_LMAN_SYM_OUTLINE -150,150,150,-150
J 0
(4600 1275);
DISPLAY 0.468085 (4600 1275);
PAINT GREEN (4600 1275);
DISPLAY INVISIBLE (4600 1275);
FORCEPROP 1 LAST NEEDS_NO_SIZE TRUE
J 0
(4750 1166);
DISPLAY 0.468085 (4750 1166);
PAINT GREEN (4750 1166);
DISPLAY INVISIBLE (4750 1166);
FORCEPROP 2 LAST CDS_LIB pure_quanta
J 0
(4600 1275);
DISPLAY INVISIBLE (4600 1275);
FORCEPROP 0 LAST CDS_LOCATION Q129
J 0
(4775 1400);
DISPLAY 1.021277 (4775 1400);
DISPLAY INVISIBLE (4775 1400);
FORCEPROP 0 LAST $SEC 2
J 0
(4775 1400);
DISPLAY 0.680851 (4775 1400);
PAINT MONO (4775 1400);
DISPLAY INVISIBLE (4775 1400);
FORCEPROP 0 LAST CDS_SEC 2
J 0
(4775 1400);
DISPLAY 1.021277 (4775 1400);
DISPLAY INVISIBLE (4775 1400);
FORCEADD MOSFET_NCH_DUAL..1
(3475 2425);
FORCEPROP 1 LAST PART_NUMBER BAM138K0003
J 0
(3626 2339);
DISPLAY 0.723404 (3626 2339);
PAINT GREEN (3626 2339);
DISPLAY INVISIBLE (3626 2339);
FORCEPROP 2 LAST PART_TYPE SMLF
J 0
(3650 2500);
DISPLAY 1.021277 (3650 2500);
FORCEPROP 2 LAST VALUE PJT138K
J 0
(3650 2450);
DISPLAY 1.021277 (3650 2450);
FORCEPROP 1 LAST MATERIAL IC
J 0
(3626 2274);
DISPLAY 0.723404 (3626 2274);
PAINT GREEN (3626 2274);
FORCEPROP 1 LAST $LOCATION Q133
J 0
(3626 2399);
DISPLAY 0.723404 (3626 2399);
PAINT GREEN (3626 2399);
FORCEPROP 0 LASTPIN (3525 2625) $PN 6
R 1
J 0
(3515 2635);
DISPLAY 0.680851 (3515 2635);
PAINT MONO (3515 2635);
FORCEPROP 0 LASTPIN (3275 2375) $PN 2
J 2
(3265 2385);
DISPLAY 0.680851 (3265 2385);
PAINT MONO (3265 2385);
FORCEPROP 0 LASTPIN (3525 2225) $PN 1
R 1
J 2
(3515 2215);
DISPLAY 0.680851 (3515 2215);
PAINT MONO (3515 2215);
FORCEPROP 1 LAST PATH I78
J 0
(3475 2425);
DISPLAY 0.723404 (3475 2425);
PAINT GREEN (3475 2425);
DISPLAY INVISIBLE (3475 2425);
FORCEPROP 1 LAST CDS_LMAN_SYM_OUTLINE -150,150,150,-150
J 0
(3475 2425);
DISPLAY 0.468085 (3475 2425);
PAINT GREEN (3475 2425);
DISPLAY INVISIBLE (3475 2425);
FORCEPROP 1 LAST NEEDS_NO_SIZE TRUE
J 0
(3475 2424);
DISPLAY 0.468085 (3475 2424);
PAINT GREEN (3475 2424);
DISPLAY INVISIBLE (3475 2424);
FORCEPROP 2 LAST CDS_LIB pure_quanta
J 0
(3475 2425);
DISPLAY INVISIBLE (3475 2425);
FORCEPROP 2 LAST CDS_LOCATION Q133
J 0
(3650 2550);
DISPLAY 1.021277 (3650 2550);
DISPLAY INVISIBLE (3650 2550);
FORCEPROP 0 LAST $SEC 1
J 0
(3650 2550);
DISPLAY 0.680851 (3650 2550);
PAINT MONO (3650 2550);
DISPLAY INVISIBLE (3650 2550);
FORCEPROP 2 LAST CDS_SEC 1
J 0
(3650 2550);
DISPLAY 1.021277 (3650 2550);
DISPLAY INVISIBLE (3650 2550);
FORCEADD UNIVERSAL_GND..1
(3525 2050);
FORCEPROP 3 LASTPIN (3525 2100) SIG_NAME GND\g
J 0
(3535 2110);
DISPLAY 0.659574 (3535 2110);
PAINT MONO (3535 2110);
DISPLAY INVISIBLE (3535 2110);
FORCEPROP 1 LAST HDL_POWER GND
J 1
(3550 1975);
DISPLAY 0.872340 (3550 1975);
PAINT GREEN (3550 1975);
DISPLAY INVISIBLE (3550 1975);
FORCEPROP 2 LAST CDS_LIB logical_power
J 0
(3525 2050);
DISPLAY INVISIBLE (3525 2050);
FORCEPROP 1 LAST PATH I79
J 0
(3600 2050);
DISPLAY 0.872340 (3600 2050);
PAINT AQUA (3600 2050);
DISPLAY INVISIBLE (3600 2050);
FORCEADD UNIVERSAL_POWER..1
(-1125 4325);
FORCEPROP 3 LASTPIN (-1125 4275) SIG_NAME P3V3_AUX\g
J 0
(-1115 4285);
DISPLAY 0.659574 (-1115 4285);
PAINT MONO (-1115 4285);
DISPLAY INVISIBLE (-1115 4285);
FORCEPROP 1 LAST HDL_POWER P3V3_AUX
J 1
(-1125 4375);
DISPLAY 0.872340 (-1125 4375);
PAINT GREEN (-1125 4375);
FORCEPROP 1 LAST PATH I8
J 0
(-1075 4350);
DISPLAY 0.872340 (-1075 4350);
PAINT AQUA (-1075 4350);
DISPLAY INVISIBLE (-1075 4350);
FORCEPROP 2 LAST CDS_LIB logical_power
J 0
(-1125 4325);
PAINT MONO (-1125 4325);
DISPLAY INVISIBLE (-1125 4325);
FORCEADD UNIVERSAL_POWER..1
(3500 1800);
FORCEPROP 3 LASTPIN (3500 1750) SIG_NAME P3V3_AUX\g
J 0
(3510 1760);
DISPLAY 0.659574 (3510 1760);
PAINT MONO (3510 1760);
DISPLAY INVISIBLE (3510 1760);
FORCEPROP 1 LAST HDL_POWER P3V3_AUX
J 1
(3500 1850);
DISPLAY 0.872340 (3500 1850);
PAINT GREEN (3500 1850);
FORCEPROP 1 LAST PATH I80
J 0
(3550 1825);
DISPLAY 0.872340 (3550 1825);
PAINT AQUA (3550 1825);
DISPLAY INVISIBLE (3550 1825);
FORCEPROP 2 LAST CDS_LIB logical_power
J 0
(3500 1800);
PAINT MONO (3500 1800);
DISPLAY INVISIBLE (3500 1800);
FORCEADD Q_RES..2
(3500 1575);
FORCEPROP 1 LAST PART_NUMBER CS24702JB10
J 0
(3540 1400);
DISPLAY 0.638298 (3540 1400);
DISPLAY INVISIBLE (3540 1400);
FORCEPROP 1 LAST MATERIAL CHIP
J 0
(3540 1500);
DISPLAY 0.638298 (3540 1500);
FORCEPROP 1 LAST WATTAGE 1/16W
J 0
(3540 1550);
DISPLAY 0.638298 (3540 1550);
FORCEPROP 1 LAST PACK_TYPE 0402LF
J 0
(3540 1450);
DISPLAY 0.638298 (3540 1450);
FORCEPROP 1 LAST TOLERANCE 5%
J 0
(3545 1600);
DISPLAY 0.638298 (3545 1600);
FORCEPROP 1 LAST VALUE 4.7K
J 0
(3545 1650);
DISPLAY 0.638298 (3545 1650);
FORCEPROP 1 LAST $LOCATION R4138
J 0
(3545 1700);
DISPLAY 0.638298 (3545 1700);
FORCEPROP 1 LASTPIN (3500 1675) $PN 1
J 0
(3505 1637);
DISPLAY 0.787234 (3505 1637);
FORCEPROP 1 LASTPIN (3500 1475) $PN 2
J 0
(3505 1485);
DISPLAY 0.787234 (3505 1485);
FORCEPROP 1 LAST PATH I81
J 0
(3550 1750);
DISPLAY 0.978723 (3550 1750);
PAINT WHITE (3550 1750);
DISPLAY INVISIBLE (3550 1750);
FORCEPROP 2 LAST CDS_LIB pure_quanta
J 0
(3500 1575);
PAINT MONO (3500 1575);
DISPLAY INVISIBLE (3500 1575);
FORCEPROP 2 LAST CDS_LOCATION R4138
J 0
(3550 1800);
DISPLAY 1.021277 (3550 1800);
DISPLAY INVISIBLE (3550 1800);
FORCEPROP 2 LAST $SEC 1
J 0
(3550 1800);
DISPLAY 0.680851 (3550 1800);
PAINT MONO (3550 1800);
DISPLAY INVISIBLE (3550 1800);
FORCEPROP 2 LAST CDS_SEC 1
J 0
(3550 1800);
DISPLAY 1.021277 (3550 1800);
DISPLAY INVISIBLE (3550 1800);
FORCEADD UNIVERSAL_GND..1
(3500 600);
FORCEPROP 3 LASTPIN (3500 650) SIG_NAME GND\g
J 0
(3510 660);
DISPLAY 0.659574 (3510 660);
PAINT MONO (3510 660);
DISPLAY INVISIBLE (3510 660);
FORCEPROP 1 LAST PATH I82
J 0
(3575 600);
DISPLAY 0.872340 (3575 600);
PAINT AQUA (3575 600);
DISPLAY INVISIBLE (3575 600);
FORCEPROP 2 LAST CDS_LIB logical_power
J 0
(3500 600);
DISPLAY INVISIBLE (3500 600);
FORCEPROP 1 LAST HDL_POWER GND
J 1
(3525 525);
DISPLAY 0.872340 (3525 525);
PAINT GREEN (3525 525);
DISPLAY INVISIBLE (3525 525);
FORCEADD MOSFET_NCH_DUAL..1
(3450 975);
FORCEPROP 1 LAST PART_NUMBER BAM138K0003
J 0
(3601 889);
DISPLAY 0.723404 (3601 889);
PAINT GREEN (3601 889);
DISPLAY INVISIBLE (3601 889);
FORCEPROP 1 LAST MATERIAL IC
J 0
(3601 824);
DISPLAY 0.723404 (3601 824);
PAINT GREEN (3601 824);
FORCEPROP 2 LAST VALUE PJT138K
J 0
(3625 1000);
DISPLAY 1.021277 (3625 1000);
FORCEPROP 2 LAST PART_TYPE SMLF
J 0
(3625 1050);
DISPLAY 1.021277 (3625 1050);
FORCEPROP 1 LAST LOCATION Q129
J 0
(3601 949);
DISPLAY 0.723404 (3601 949);
PAINT GREEN (3601 949);
FORCEPROP 0 LASTPIN (3500 1175) $PN 6
R 1
J 0
(3490 1185);
DISPLAY 0.680851 (3490 1185);
PAINT MONO (3490 1185);
FORCEPROP 0 LASTPIN (3250 925) $PN 2
J 2
(3240 935);
DISPLAY 0.680851 (3240 935);
PAINT MONO (3240 935);
FORCEPROP 0 LASTPIN (3500 775) $PN 1
R 1
J 2
(3490 765);
DISPLAY 0.680851 (3490 765);
PAINT MONO (3490 765);
FORCEPROP 1 LAST PATH I83
J 0
(3450 975);
DISPLAY 0.723404 (3450 975);
PAINT GREEN (3450 975);
DISPLAY INVISIBLE (3450 975);
FORCEPROP 2 LAST CDS_LIB pure_quanta
J 0
(3450 975);
DISPLAY INVISIBLE (3450 975);
FORCEPROP 1 LAST NEEDS_NO_SIZE TRUE
J 0
(3450 974);
DISPLAY 0.468085 (3450 974);
PAINT GREEN (3450 974);
DISPLAY INVISIBLE (3450 974);
FORCEPROP 1 LAST CDS_LMAN_SYM_OUTLINE -150,150,150,-150
J 0
(3450 975);
DISPLAY 0.468085 (3450 975);
PAINT GREEN (3450 975);
DISPLAY INVISIBLE (3450 975);
FORCEPROP 0 LAST $SEC 1
J 0
(3625 1100);
DISPLAY 0.680851 (3625 1100);
PAINT MONO (3625 1100);
DISPLAY INVISIBLE (3625 1100);
FORCEPROP 2 LAST CDS_SEC 1
J 0
(3625 1100);
DISPLAY 1.021277 (3625 1100);
DISPLAY INVISIBLE (3625 1100);
FORCEADD UNIVERSAL_POWER..1
(2325 4275);
FORCEPROP 3 LASTPIN (2325 4225) SIG_NAME P3V3_AUX\g
J 0
(2335 4235);
DISPLAY 0.659574 (2335 4235);
PAINT MONO (2335 4235);
DISPLAY INVISIBLE (2335 4235);
FORCEPROP 1 LAST HDL_POWER P3V3_AUX
J 1
(2325 4325);
DISPLAY 0.872340 (2325 4325);
PAINT GREEN (2325 4325);
FORCEPROP 2 LAST CDS_LIB logical_power
J 0
(2325 4275);
PAINT MONO (2325 4275);
DISPLAY INVISIBLE (2325 4275);
FORCEPROP 1 LAST PATH I84
J 0
(2375 4300);
DISPLAY 0.872340 (2375 4300);
PAINT AQUA (2375 4300);
DISPLAY INVISIBLE (2375 4300);
FORCEADD Q_RES..2
(2325 4025);
FORCEPROP 1 LAST PART_NUMBER CS35492FB03
J 0
(2365 3900);
DISPLAY 0.787234 (2365 3900);
DISPLAY INVISIBLE (2365 3900);
FORCEPROP 1 LAST TOLERANCE 1%
J 0
(2370 4050);
DISPLAY 0.787234 (2370 4050);
FORCEPROP 1 LAST VALUE 54.9K
J 0
(2370 4100);
DISPLAY 0.787234 (2370 4100);
FORCEPROP 1 LAST PACK_TYPE 0402LF
J 0
(2365 3850);
DISPLAY 0.787234 (2365 3850);
FORCEPROP 1 LAST MATERIAL EMPTY
J 0
(2365 3950);
DISPLAY 0.787234 (2365 3950);
PAINT RED (2365 3950);
FORCEPROP 1 LAST WATTAGE 1/16W
J 0
(2365 4000);
DISPLAY 0.787234 (2365 4000);
FORCEPROP 1 LAST $LOCATION R4131
J 0
(2370 4150);
DISPLAY 0.978723 (2370 4150);
FORCEPROP 1 LASTPIN (2325 4125) $PN 1
J 0
(2330 4087);
DISPLAY 0.787234 (2330 4087);
PAINT MONO (2330 4087);
FORCEPROP 1 LASTPIN (2325 3925) $PN 2
J 0
(2330 3935);
DISPLAY 0.787234 (2330 3935);
PAINT MONO (2330 3935);
FORCEPROP 2 LAST CDS_LIB pure_quanta
J 0
(2325 4025);
DISPLAY INVISIBLE (2325 4025);
FORCEPROP 1 LAST PATH I85
J 0
(2375 4200);
DISPLAY 0.978723 (2375 4200);
PAINT WHITE (2375 4200);
DISPLAY INVISIBLE (2375 4200);
FORCEPROP 0 LAST CDS_LOCATION R4131
J 0
(2375 4200);
DISPLAY 1.021277 (2375 4200);
DISPLAY INVISIBLE (2375 4200);
FORCEPROP 0 LAST $SEC 1
J 0
(2375 4200);
DISPLAY 0.680851 (2375 4200);
PAINT MONO (2375 4200);
DISPLAY INVISIBLE (2375 4200);
FORCEPROP 0 LAST CDS_SEC 1
J 0
(2375 4200);
DISPLAY 1.021277 (2375 4200);
DISPLAY INVISIBLE (2375 4200);
FORCEADD Q_RES..2
(2350 3550);
FORCEPROP 1 LAST PART_NUMBER CS41002FB09
J 0
(2390 3425);
DISPLAY 0.510638 (2390 3425);
DISPLAY INVISIBLE (2390 3425);
FORCEPROP 1 LAST WATTAGE 1/16W
J 0
(2390 3525);
DISPLAY 0.510638 (2390 3525);
FORCEPROP 1 LAST TOLERANCE 1%
J 0
(2395 3575);
DISPLAY 0.510638 (2395 3575);
FORCEPROP 1 LAST VALUE 100K
J 0
(2395 3625);
DISPLAY 0.510638 (2395 3625);
FORCEPROP 1 LAST MATERIAL EMPTY
J 0
(2390 3475);
DISPLAY 0.510638 (2390 3475);
PAINT RED (2390 3475);
FORCEPROP 1 LAST PACK_TYPE 0402LF
J 0
(2390 3375);
DISPLAY 0.510638 (2390 3375);
FORCEPROP 1 LAST $LOCATION R4132
J 0
(2395 3675);
DISPLAY 0.978723 (2395 3675);
FORCEPROP 1 LASTPIN (2350 3650) $PN 1
J 0
(2355 3612);
DISPLAY 0.787234 (2355 3612);
PAINT MONO (2355 3612);
FORCEPROP 1 LASTPIN (2350 3450) $PN 2
J 0
(2355 3460);
DISPLAY 0.787234 (2355 3460);
PAINT MONO (2355 3460);
FORCEPROP 1 LAST PATH I86
J 0
(2400 3725);
DISPLAY 0.978723 (2400 3725);
PAINT WHITE (2400 3725);
DISPLAY INVISIBLE (2400 3725);
FORCEPROP 2 LAST CDS_LIB pure_quanta
J 0
(2350 3550);
DISPLAY INVISIBLE (2350 3550);
FORCEPROP 0 LAST CDS_LOCATION R4132
J 0
(2400 3725);
DISPLAY 1.021277 (2400 3725);
DISPLAY INVISIBLE (2400 3725);
FORCEPROP 0 LAST $SEC 1
J 0
(2400 3725);
DISPLAY 0.680851 (2400 3725);
PAINT MONO (2400 3725);
DISPLAY INVISIBLE (2400 3725);
FORCEPROP 0 LAST CDS_SEC 1
J 0
(2400 3725);
DISPLAY 1.021277 (2400 3725);
DISPLAY INVISIBLE (2400 3725);
FORCEADD OFFPAGE..4
R 2
(2075 3750);
FORCEPROP 2 LAST $XR0 139 
J 0
(1793 3750);
DISPLAY 0.638298 (1793 3750);
PAINT MONO (1793 3750);
FORCEPROP 2 LAST CDS_LIB standard
J 0
(2075 3750);
DISPLAY INVISIBLE (2075 3750);
FORCEPROP 1 LAST COMMENT_BODY TRUE
J 2
(2100 3650);
DISPLAY 0.872340 (2100 3650);
PAINT GREEN (2100 3650);
DISPLAY INVISIBLE (2100 3650);
FORCEPROP 1 LAST OFFPAGE TRUE
J 2
(1750 3625);
DISPLAY 0.872340 (1750 3625);
PAINT GREEN (1750 3625);
DISPLAY INVISIBLE (1750 3625);
FORCEPROP 2 LAST PATH I87
J 0
(1800 3800);
DISPLAY 1.021277 (1800 3800);
DISPLAY INVISIBLE (1800 3800);
FORCEADD UNIVERSAL_GND..1
(2350 3275);
FORCEPROP 3 LASTPIN (2350 3325) SIG_NAME GND\g
J 0
(2360 3335);
DISPLAY 0.659574 (2360 3335);
PAINT MONO (2360 3335);
DISPLAY INVISIBLE (2360 3335);
FORCEPROP 1 LAST PATH I88
J 0
(2425 3275);
DISPLAY 0.872340 (2425 3275);
PAINT AQUA (2425 3275);
DISPLAY INVISIBLE (2425 3275);
FORCEPROP 1 LAST HDL_POWER GND
J 1
(2375 3200);
DISPLAY 0.872340 (2375 3200);
PAINT GREEN (2375 3200);
DISPLAY INVISIBLE (2375 3200);
FORCEPROP 2 LAST CDS_LIB logical_power
J 0
(2350 3275);
DISPLAY INVISIBLE (2350 3275);
FORCEADD UNIVERSAL_POWER..1
(2350 2900);
FORCEPROP 3 LASTPIN (2350 2850) SIG_NAME P3V3_AUX\g
J 0
(2360 2860);
DISPLAY 0.659574 (2360 2860);
PAINT MONO (2360 2860);
DISPLAY INVISIBLE (2360 2860);
FORCEPROP 1 LAST HDL_POWER P3V3_AUX
J 1
(2350 2950);
DISPLAY 0.872340 (2350 2950);
PAINT GREEN (2350 2950);
FORCEPROP 2 LAST CDS_LIB logical_power
J 0
(2350 2900);
PAINT MONO (2350 2900);
DISPLAY INVISIBLE (2350 2900);
FORCEPROP 1 LAST PATH I89
J 0
(2400 2925);
DISPLAY 0.872340 (2400 2925);
PAINT AQUA (2400 2925);
DISPLAY INVISIBLE (2400 2925);
FORCEADD Q_RES..2
(-1125 4100);
FORCEPROP 1 LAST PART_NUMBER CS24702JB10
J 0
(-1085 3925);
DISPLAY 0.638298 (-1085 3925);
DISPLAY INVISIBLE (-1085 3925);
FORCEPROP 1 LAST VALUE 4.7K
J 0
(-1080 4175);
DISPLAY 0.638298 (-1080 4175);
FORCEPROP 1 LAST TOLERANCE 5%
J 0
(-1080 4125);
DISPLAY 0.638298 (-1080 4125);
FORCEPROP 1 LAST WATTAGE 1/16W
J 0
(-1085 4075);
DISPLAY 0.638298 (-1085 4075);
FORCEPROP 1 LAST MATERIAL CHIP
J 0
(-1085 4025);
DISPLAY 0.638298 (-1085 4025);
FORCEPROP 1 LAST PACK_TYPE 0402LF
J 0
(-1085 3975);
DISPLAY 0.638298 (-1085 3975);
FORCEPROP 1 LAST $LOCATION R4125
J 0
(-1080 4225);
DISPLAY 0.638298 (-1080 4225);
FORCEPROP 1 LASTPIN (-1125 4200) $PN 1
J 0
(-1120 4162);
DISPLAY 0.787234 (-1120 4162);
FORCEPROP 1 LASTPIN (-1125 4000) $PN 2
J 0
(-1120 4010);
DISPLAY 0.787234 (-1120 4010);
FORCEPROP 2 LAST CDS_LIB pure_quanta
J 0
(-1125 4100);
PAINT MONO (-1125 4100);
DISPLAY INVISIBLE (-1125 4100);
FORCEPROP 1 LAST PATH I9
J 0
(-1075 4275);
DISPLAY 0.978723 (-1075 4275);
PAINT WHITE (-1075 4275);
DISPLAY INVISIBLE (-1075 4275);
FORCEPROP 2 LAST CDS_LOCATION R4125
J 0
(-1075 4325);
DISPLAY 1.021277 (-1075 4325);
DISPLAY INVISIBLE (-1075 4325);
FORCEPROP 2 LAST $SEC 1
J 0
(-1075 4325);
DISPLAY 0.680851 (-1075 4325);
PAINT MONO (-1075 4325);
DISPLAY INVISIBLE (-1075 4325);
FORCEPROP 2 LAST CDS_SEC 1
J 0
(-1075 4325);
DISPLAY 1.021277 (-1075 4325);
DISPLAY INVISIBLE (-1075 4325);
FORCEADD Q_RES..2
(2375 2175);
FORCEPROP 1 LAST PART_NUMBER CS41002FB09
J 0
(2415 2050);
DISPLAY 0.510638 (2415 2050);
DISPLAY INVISIBLE (2415 2050);
FORCEPROP 1 LAST MATERIAL EMPTY
J 0
(2415 2100);
DISPLAY 0.510638 (2415 2100);
PAINT RED (2415 2100);
FORCEPROP 1 LAST PACK_TYPE 0402LF
J 0
(2415 2000);
DISPLAY 0.510638 (2415 2000);
FORCEPROP 1 LAST WATTAGE 1/16W
J 0
(2415 2150);
DISPLAY 0.510638 (2415 2150);
FORCEPROP 1 LAST VALUE 100K
J 0
(2420 2250);
DISPLAY 0.510638 (2420 2250);
FORCEPROP 1 LAST TOLERANCE 1%
J 0
(2420 2200);
DISPLAY 0.510638 (2420 2200);
FORCEPROP 1 LAST $LOCATION R4136
J 0
(2420 2300);
DISPLAY 0.978723 (2420 2300);
FORCEPROP 1 LASTPIN (2375 2275) $PN 1
J 0
(2380 2237);
DISPLAY 0.787234 (2380 2237);
PAINT MONO (2380 2237);
FORCEPROP 1 LASTPIN (2375 2075) $PN 2
J 0
(2380 2085);
DISPLAY 0.787234 (2380 2085);
PAINT MONO (2380 2085);
FORCEPROP 1 LAST PATH I91
J 0
(2425 2350);
DISPLAY 0.978723 (2425 2350);
PAINT WHITE (2425 2350);
DISPLAY INVISIBLE (2425 2350);
FORCEPROP 2 LAST CDS_LIB pure_quanta
J 0
(2375 2175);
DISPLAY INVISIBLE (2375 2175);
FORCEPROP 0 LAST CDS_LOCATION R4136
J 0
(2425 2350);
DISPLAY 1.021277 (2425 2350);
DISPLAY INVISIBLE (2425 2350);
FORCEPROP 0 LAST $SEC 1
J 0
(2425 2350);
DISPLAY 0.680851 (2425 2350);
PAINT MONO (2425 2350);
DISPLAY INVISIBLE (2425 2350);
FORCEPROP 0 LAST CDS_SEC 1
J 0
(2425 2350);
DISPLAY 1.021277 (2425 2350);
DISPLAY INVISIBLE (2425 2350);
FORCEADD UNIVERSAL_GND..1
(2375 1900);
FORCEPROP 3 LASTPIN (2375 1950) SIG_NAME GND\g
J 0
(2385 1960);
DISPLAY 0.659574 (2385 1960);
PAINT MONO (2385 1960);
DISPLAY INVISIBLE (2385 1960);
FORCEPROP 1 LAST PATH I92
J 0
(2450 1900);
DISPLAY 0.872340 (2450 1900);
PAINT AQUA (2450 1900);
DISPLAY INVISIBLE (2450 1900);
FORCEPROP 1 LAST HDL_POWER GND
J 1
(2400 1825);
DISPLAY 0.872340 (2400 1825);
PAINT GREEN (2400 1825);
DISPLAY INVISIBLE (2400 1825);
FORCEPROP 2 LAST CDS_LIB logical_power
J 0
(2375 1900);
DISPLAY INVISIBLE (2375 1900);
FORCEADD UNIVERSAL_POWER..1
(2325 1450);
FORCEPROP 3 LASTPIN (2325 1400) SIG_NAME P3V3_AUX\g
J 0
(2335 1410);
DISPLAY 0.659574 (2335 1410);
PAINT MONO (2335 1410);
DISPLAY INVISIBLE (2335 1410);
FORCEPROP 1 LAST HDL_POWER P3V3_AUX
J 1
(2325 1500);
DISPLAY 0.872340 (2325 1500);
PAINT GREEN (2325 1500);
FORCEPROP 1 LAST PATH I93
J 0
(2375 1475);
DISPLAY 0.872340 (2375 1475);
PAINT AQUA (2375 1475);
DISPLAY INVISIBLE (2375 1475);
FORCEPROP 2 LAST CDS_LIB logical_power
J 0
(2325 1450);
PAINT MONO (2325 1450);
DISPLAY INVISIBLE (2325 1450);
FORCEADD OFFPAGE..4
R 2
(2100 2375);
FORCEPROP 2 LAST $XR0 139 
J 0
(1848 2375);
DISPLAY 0.638298 (1848 2375);
PAINT MONO (1848 2375);
FORCEPROP 2 LAST CDS_LIB standard
J 0
(2100 2375);
DISPLAY INVISIBLE (2100 2375);
FORCEPROP 1 LAST COMMENT_BODY TRUE
J 2
(2125 2275);
DISPLAY 0.872340 (2125 2275);
PAINT GREEN (2125 2275);
DISPLAY INVISIBLE (2125 2275);
FORCEPROP 1 LAST OFFPAGE TRUE
J 2
(1775 2250);
DISPLAY 0.872340 (1775 2250);
PAINT GREEN (1775 2250);
DISPLAY INVISIBLE (1775 2250);
FORCEPROP 2 LAST PATH I94
J 0
(1825 2425);
DISPLAY 1.021277 (1825 2425);
DISPLAY INVISIBLE (1825 2425);
FORCEADD Q_RES..2
(2325 1200);
FORCEPROP 1 LAST PART_NUMBER CS35492FB03
J 0
(2365 1075);
DISPLAY 0.787234 (2365 1075);
DISPLAY INVISIBLE (2365 1075);
FORCEPROP 1 LAST VALUE 54.9K
J 0
(2370 1275);
DISPLAY 0.787234 (2370 1275);
FORCEPROP 1 LAST TOLERANCE 1%
J 0
(2370 1225);
DISPLAY 0.787234 (2370 1225);
FORCEPROP 1 LAST PACK_TYPE 0402LF
J 0
(2365 1025);
DISPLAY 0.787234 (2365 1025);
FORCEPROP 1 LAST MATERIAL EMPTY
J 0
(2365 1125);
DISPLAY 0.787234 (2365 1125);
PAINT RED (2365 1125);
FORCEPROP 1 LAST WATTAGE 1/16W
J 0
(2365 1175);
DISPLAY 0.787234 (2365 1175);
FORCEPROP 1 LAST $LOCATION R4133
J 0
(2370 1325);
DISPLAY 0.978723 (2370 1325);
FORCEPROP 1 LASTPIN (2325 1300) $PN 1
J 0
(2330 1262);
DISPLAY 0.787234 (2330 1262);
PAINT MONO (2330 1262);
FORCEPROP 1 LASTPIN (2325 1100) $PN 2
J 0
(2330 1110);
DISPLAY 0.787234 (2330 1110);
PAINT MONO (2330 1110);
FORCEPROP 1 LAST PATH I95
J 0
(2375 1375);
DISPLAY 0.978723 (2375 1375);
PAINT WHITE (2375 1375);
DISPLAY INVISIBLE (2375 1375);
FORCEPROP 2 LAST CDS_LIB pure_quanta
J 0
(2325 1200);
DISPLAY INVISIBLE (2325 1200);
FORCEPROP 0 LAST CDS_LOCATION R4133
J 0
(2375 1375);
DISPLAY 1.021277 (2375 1375);
DISPLAY INVISIBLE (2375 1375);
FORCEPROP 0 LAST $SEC 1
J 0
(2375 1375);
DISPLAY 0.680851 (2375 1375);
PAINT MONO (2375 1375);
DISPLAY INVISIBLE (2375 1375);
FORCEPROP 0 LAST CDS_SEC 1
J 0
(2375 1375);
DISPLAY 1.021277 (2375 1375);
DISPLAY INVISIBLE (2375 1375);
FORCEADD Q_RES..2
(2350 725);
FORCEPROP 1 LAST PART_NUMBER CS41002FB09
J 0
(2390 600);
DISPLAY 0.510638 (2390 600);
DISPLAY INVISIBLE (2390 600);
FORCEPROP 1 LAST WATTAGE 1/16W
J 0
(2390 700);
DISPLAY 0.510638 (2390 700);
FORCEPROP 1 LAST PACK_TYPE 0402LF
J 0
(2390 550);
DISPLAY 0.510638 (2390 550);
FORCEPROP 1 LAST TOLERANCE 1%
J 0
(2395 750);
DISPLAY 0.510638 (2395 750);
FORCEPROP 1 LAST MATERIAL EMPTY
J 0
(2390 650);
DISPLAY 0.510638 (2390 650);
PAINT RED (2390 650);
FORCEPROP 1 LAST VALUE 100K
J 0
(2395 800);
DISPLAY 0.510638 (2395 800);
FORCEPROP 1 LAST $LOCATION R4134
J 0
(2395 850);
DISPLAY 0.978723 (2395 850);
FORCEPROP 1 LASTPIN (2350 825) $PN 1
J 0
(2355 787);
DISPLAY 0.787234 (2355 787);
PAINT MONO (2355 787);
FORCEPROP 1 LASTPIN (2350 625) $PN 2
J 0
(2355 635);
DISPLAY 0.787234 (2355 635);
PAINT MONO (2355 635);
FORCEPROP 1 LAST PATH I96
J 0
(2400 900);
DISPLAY 0.978723 (2400 900);
PAINT WHITE (2400 900);
DISPLAY INVISIBLE (2400 900);
FORCEPROP 2 LAST CDS_LIB pure_quanta
J 0
(2350 725);
DISPLAY INVISIBLE (2350 725);
FORCEPROP 0 LAST CDS_LOCATION R4134
J 0
(2400 900);
DISPLAY 1.021277 (2400 900);
DISPLAY INVISIBLE (2400 900);
FORCEPROP 0 LAST $SEC 1
J 0
(2400 900);
DISPLAY 0.680851 (2400 900);
PAINT MONO (2400 900);
DISPLAY INVISIBLE (2400 900);
FORCEPROP 0 LAST CDS_SEC 1
J 0
(2400 900);
DISPLAY 1.021277 (2400 900);
DISPLAY INVISIBLE (2400 900);
FORCEADD UNIVERSAL_GND..1
(2350 450);
FORCEPROP 3 LASTPIN (2350 500) SIG_NAME GND\g
J 0
(2360 510);
DISPLAY 0.659574 (2360 510);
PAINT MONO (2360 510);
DISPLAY INVISIBLE (2360 510);
FORCEPROP 1 LAST PATH I97
J 0
(2425 450);
DISPLAY 0.872340 (2425 450);
PAINT AQUA (2425 450);
DISPLAY INVISIBLE (2425 450);
FORCEPROP 2 LAST CDS_LIB logical_power
J 0
(2350 450);
DISPLAY INVISIBLE (2350 450);
FORCEPROP 1 LAST HDL_POWER GND
J 1
(2375 375);
DISPLAY 0.872340 (2375 375);
PAINT GREEN (2375 375);
DISPLAY INVISIBLE (2375 375);
FORCEADD OFFPAGE..4
R 2
(2075 925);
FORCEPROP 2 LAST $XR0 139 
J 0
(1793 925);
DISPLAY 0.638298 (1793 925);
PAINT MONO (1793 925);
FORCEPROP 2 LAST PATH I98
J 0
(1800 975);
DISPLAY 1.021277 (1800 975);
DISPLAY INVISIBLE (1800 975);
FORCEPROP 1 LAST OFFPAGE TRUE
J 2
(1750 800);
DISPLAY 0.872340 (1750 800);
PAINT GREEN (1750 800);
DISPLAY INVISIBLE (1750 800);
FORCEPROP 1 LAST COMMENT_BODY TRUE
J 2
(2100 825);
DISPLAY 0.872340 (2100 825);
PAINT GREEN (2100 825);
DISPLAY INVISIBLE (2100 825);
FORCEPROP 2 LAST CDS_LIB standard
J 0
(2075 925);
DISPLAY INVISIBLE (2075 925);
FORCEADD MOSFET_NCH_DUAL..1
(-1100 -875);
FORCEPROP 1 LAST PART_NUMBER BAM138K0003
J 0
(-949 -961);
DISPLAY 0.723404 (-949 -961);
PAINT GREEN (-949 -961);
DISPLAY INVISIBLE (-949 -961);
FORCEPROP 2 LAST PART_TYPE SMLF
J 0
(-925 -800);
DISPLAY 1.021277 (-925 -800);
FORCEPROP 1 LAST MATERIAL IC
J 0
(-949 -1026);
DISPLAY 0.723404 (-949 -1026);
PAINT GREEN (-949 -1026);
FORCEPROP 2 LAST VALUE PJT138K
J 0
(-925 -850);
DISPLAY 1.021277 (-925 -850);
FORCEPROP 1 LAST $LOCATION Q134
J 0
(-949 -901);
DISPLAY 0.723404 (-949 -901);
PAINT GREEN (-949 -901);
FORCEPROP 0 LASTPIN (-1050 -675) $PN 6
R 1
J 0
(-1060 -665);
DISPLAY 0.680851 (-1060 -665);
PAINT MONO (-1060 -665);
FORCEPROP 0 LASTPIN (-1300 -925) $PN 2
J 2
(-1310 -915);
DISPLAY 0.680851 (-1310 -915);
PAINT MONO (-1310 -915);
FORCEPROP 0 LASTPIN (-1050 -1075) $PN 1
R 1
J 2
(-1060 -1085);
DISPLAY 0.680851 (-1060 -1085);
PAINT MONO (-1060 -1085);
FORCEPROP 1 LAST PATH I99
J 0
(-1100 -875);
DISPLAY 0.723404 (-1100 -875);
PAINT GREEN (-1100 -875);
DISPLAY INVISIBLE (-1100 -875);
FORCEPROP 2 LAST CDS_LIB pure_quanta
J 0
(-1100 -875);
DISPLAY INVISIBLE (-1100 -875);
FORCEPROP 1 LAST NEEDS_NO_SIZE TRUE
J 0
(-1100 -876);
DISPLAY 0.468085 (-1100 -876);
PAINT GREEN (-1100 -876);
DISPLAY INVISIBLE (-1100 -876);
FORCEPROP 1 LAST CDS_LMAN_SYM_OUTLINE -150,150,150,-150
J 0
(-1100 -875);
DISPLAY 0.468085 (-1100 -875);
PAINT GREEN (-1100 -875);
DISPLAY INVISIBLE (-1100 -875);
FORCEPROP 2 LAST CDS_LOCATION Q134
J 0
(-925 -750);
DISPLAY 1.021277 (-925 -750);
DISPLAY INVISIBLE (-925 -750);
FORCEPROP 0 LAST $SEC 1
J 0
(-925 -750);
DISPLAY 0.680851 (-925 -750);
PAINT MONO (-925 -750);
DISPLAY INVISIBLE (-925 -750);
FORCEPROP 2 LAST CDS_SEC 1
J 0
(-925 -750);
DISPLAY 1.021277 (-925 -750);
DISPLAY INVISIBLE (-925 -750);
FORCEADD QUANTA_TITLE_BLOCK_C..1
(6500 -1700);
FORCEPROP 0 LAST CDS_CON_LAST_MODIFIED Fri Aug 25 14:02:07 2023
J 0
(4615 -1685);
PAINT MONO (4615 -1685);
DISPLAY INVISIBLE (4615 -1685);
FORCEPROP 1 LAST CUSTOM_TXT_CDS <CON_LAST_MODIFIED>
J 0
(4615 -1685);
DISPLAY 0.978723 (4615 -1685);
FORCEPROP 2 LAST CUSTOM_TXT_CDS <XR_PAGE_TITLE>
J 0
(-1390 3550);
DISPLAY 0.638298 (-1390 3550);
PAINT PINK (-1390 3550);
DISPLAY INVISIBLE (-1390 3550);
FORCEPROP 2 LAST CUSTOM_TXT_CDS <NAME_2>
J 0
(3325 -1650);
FORCEPROP 2 LAST CUSTOM_TXT_CDS <Q_PROJ>
J 0
(4118 -1598);
DISPLAY 1.212766 (4118 -1598);
FORCEPROP 2 LAST CUSTOM_TXT_CDS <Q_NUMBER>
J 0
(5097 -1597);
DISPLAY 1.212766 (5097 -1597);
FORCEPROP 2 LAST CUSTOM_TXT_CDS <CON_PAGE_NUM> OF <CON_TOTAL_PAGES>
J 0
(6054 -1682);
DISPLAY 0.978723 (6054 -1682);
FORCEPROP 2 LAST CUSTOM_TXT_CDS <Q_REV>
J 0
(6316 -1597);
DISPLAY 1.212766 (6316 -1597);
FORCEPROP 2 LAST CUSTOM_TXT_CDS <NAME_1>
J 0
(3325 -1525);
FORCEPROP 1 LAST Q_TITLE EXAMAX_ISO (2/7)
J 0
(-2750 -1625);
DISPLAY 1.957447 (-2750 -1625);
PAINT GREEN (-2750 -1625);
FORCEPROP 1 LAST Q_DEPT 
J 1
(2737 -1651);
DISPLAY 1.957447 (2737 -1651);
PAINT GREEN (2737 -1651);
FORCEPROP 2 LAST CDS_XR_PAGE_TITLE CR-146 : @S9S_MB_2U_LIB.S9S_MB_2U(SCH_1):PAGE146
J 0
(-1390 3550);
DISPLAY 0.638298 (-1390 3550);
PAINT PINK (-1390 3550);
DISPLAY INVISIBLE (-1390 3550);
FORCEPROP 1 LAST COMMENT_BODY TRUE
J 0
(6512 -1713);
DISPLAY 0.978723 (6512 -1713);
PAINT GREEN (6512 -1713);
DISPLAY INVISIBLE (6512 -1713);
FORCEPROP 2 LAST PAGE_BORDER TRUE
J 0
(-1390 3550);
DISPLAY 0.638298 (-1390 3550);
PAINT PINK (-1390 3550);
DISPLAY INVISIBLE (-1390 3550);
FORCEPROP 1 LAST CDS_LMAN_SYM_OUTLINE -9475,6775,100,-125
J 0
(6500 -1700);
DISPLAY 0.468085 (6500 -1700);
PAINT GREEN (6500 -1700);
DISPLAY INVISIBLE (6500 -1700);
FORCEPROP 2 LAST CDS_LIB pure_quanta
J 0
(6500 -1700);
PAINT MONO (6500 -1700);
DISPLAY INVISIBLE (6500 -1700);
FORCEADD DNS..2
(-725 175);
PAINT RED (-725 175);
FORCEPROP 2 LAST CDS_LIB mstr_misc
J 0
(-725 175);
DISPLAY INVISIBLE (-725 175);
FORCEPROP 1 LAST COMMENT_BODY TRUE
J 0
(-725 175);
DISPLAY INVISIBLE (-725 175);
FORCEADD DNS..2
(2325 -300);
PAINT RED (2325 -300);
FORCEPROP 1 LAST COMMENT_BODY TRUE
J 0
(2325 -300);
DISPLAY INVISIBLE (2325 -300);
FORCEPROP 2 LAST CDS_LIB mstr_misc
J 0
(2325 -300);
DISPLAY INVISIBLE (2325 -300);
FORCEADD DNS..2
(5425 -275);
PAINT RED (5425 -275);
FORCEPROP 1 LAST COMMENT_BODY TRUE
J 0
(5425 -275);
DISPLAY INVISIBLE (5425 -275);
FORCEPROP 2 LAST CDS_LIB mstr_misc
J 0
(5425 -275);
DISPLAY INVISIBLE (5425 -275);
FORCEADD DNS..2
(2350 700);
PAINT RED (2350 700);
FORCEPROP 1 LAST COMMENT_BODY TRUE
J 0
(2350 700);
DISPLAY INVISIBLE (2350 700);
FORCEPROP 2 LAST CDS_LIB mstr_misc
J 0
(2350 700);
DISPLAY INVISIBLE (2350 700);
FORCEADD DNS..2
(5425 1200);
PAINT RED (5425 1200);
FORCEPROP 2 LAST CDS_LIB mstr_misc
J 0
(5425 1200);
DISPLAY INVISIBLE (5425 1200);
FORCEPROP 1 LAST COMMENT_BODY TRUE
J 0
(5425 1200);
DISPLAY INVISIBLE (5425 1200);
FORCEADD DNS..2
(2325 1175);
PAINT RED (2325 1175);
FORCEPROP 1 LAST COMMENT_BODY TRUE
J 0
(2325 1175);
DISPLAY INVISIBLE (2325 1175);
FORCEPROP 2 LAST CDS_LIB mstr_misc
J 0
(2325 1175);
DISPLAY INVISIBLE (2325 1175);
FORCEADD DNS..2
(-2275 2325);
PAINT RED (-2275 2325);
FORCEPROP 2 LAST CDS_LIB mstr_misc
J 0
(-2275 2325);
DISPLAY INVISIBLE (-2275 2325);
FORCEPROP 1 LAST COMMENT_BODY TRUE
J 0
(-2275 2325);
DISPLAY INVISIBLE (-2275 2325);
FORCEADD DNS..2
(2350 3525);
PAINT RED (2350 3525);
FORCEPROP 2 LAST CDS_LIB mstr_misc
J 0
(2350 3525);
DISPLAY INVISIBLE (2350 3525);
FORCEPROP 1 LAST COMMENT_BODY TRUE
J 0
(2350 3525);
DISPLAY INVISIBLE (2350 3525);
FORCEADD DNS..2
(2375 2150);
PAINT RED (2375 2150);
FORCEPROP 2 LAST CDS_LIB mstr_misc
J 0
(2375 2150);
DISPLAY INVISIBLE (2375 2150);
FORCEPROP 1 LAST COMMENT_BODY TRUE
J 0
(2375 2150);
DISPLAY INVISIBLE (2375 2150);
FORCEADD DNS..2
(-2200 -1150);
PAINT RED (-2200 -1150);
FORCEPROP 1 LAST COMMENT_BODY TRUE
J 0
(-2200 -1150);
DISPLAY INVISIBLE (-2200 -1150);
FORCEPROP 2 LAST CDS_LIB mstr_misc
J 0
(-2200 -1150);
DISPLAY INVISIBLE (-2200 -1150);
FORCEADD DNS..2
(-2275 400);
PAINT RED (-2275 400);
FORCEPROP 2 LAST CDS_LIB mstr_misc
J 0
(-2275 400);
DISPLAY INVISIBLE (-2275 400);
FORCEPROP 1 LAST COMMENT_BODY TRUE
J 0
(-2275 400);
DISPLAY INVISIBLE (-2275 400);
FORCEADD DNS..2
(-2250 1850);
PAINT RED (-2250 1850);
FORCEPROP 1 LAST COMMENT_BODY TRUE
J 0
(-2250 1850);
DISPLAY INVISIBLE (-2250 1850);
FORCEPROP 2 LAST CDS_LIB mstr_misc
J 0
(-2250 1850);
DISPLAY INVISIBLE (-2250 1850);
FORCEADD DNS..2
(-2275 3225);
PAINT RED (-2275 3225);
FORCEPROP 1 LAST COMMENT_BODY TRUE
J 0
(-2275 3225);
DISPLAY INVISIBLE (-2275 3225);
FORCEPROP 2 LAST CDS_LIB mstr_misc
J 0
(-2275 3225);
DISPLAY INVISIBLE (-2275 3225);
FORCEADD DNS..2
(875 -650);
PAINT RED (875 -650);
FORCEPROP 2 LAST CDS_LIB mstr_misc
J 0
(875 -650);
DISPLAY INVISIBLE (875 -650);
FORCEPROP 1 LAST COMMENT_BODY TRUE
J 0
(875 -650);
DISPLAY INVISIBLE (875 -650);
FORCEADD DNS..2
(800 900);
PAINT RED (800 900);
FORCEPROP 1 LAST COMMENT_BODY TRUE
J 0
(800 900);
DISPLAY INVISIBLE (800 900);
FORCEPROP 2 LAST CDS_LIB mstr_misc
J 0
(800 900);
DISPLAY INVISIBLE (800 900);
FORCEADD DNS..2
(5425 4025);
PAINT RED (5425 4025);
FORCEPROP 1 LAST COMMENT_BODY TRUE
J 0
(5425 4025);
DISPLAY INVISIBLE (5425 4025);
FORCEPROP 2 LAST CDS_LIB mstr_misc
J 0
(5425 4025);
DISPLAY INVISIBLE (5425 4025);
FORCEADD DNS..2
(5450 2650);
PAINT RED (5450 2650);
FORCEPROP 1 LAST COMMENT_BODY TRUE
J 0
(5450 2650);
DISPLAY INVISIBLE (5450 2650);
FORCEPROP 2 LAST CDS_LIB mstr_misc
J 0
(5450 2650);
DISPLAY INVISIBLE (5450 2650);
FORCEADD DNS..2
(2325 4000);
PAINT RED (2325 4000);
FORCEPROP 2 LAST CDS_LIB mstr_misc
J 0
(2325 4000);
DISPLAY INVISIBLE (2325 4000);
FORCEPROP 1 LAST COMMENT_BODY TRUE
J 0
(2325 4000);
DISPLAY INVISIBLE (2325 4000);
FORCEADD DNS..2
(-2300 3700);
PAINT RED (-2300 3700);
FORCEPROP 1 LAST COMMENT_BODY TRUE
J 0
(-2300 3700);
DISPLAY INVISIBLE (-2300 3700);
FORCEPROP 2 LAST CDS_LIB mstr_misc
J 0
(-2300 3700);
DISPLAY INVISIBLE (-2300 3700);
FORCEADD DNS..2
(825 2350);
PAINT RED (825 2350);
FORCEPROP 2 LAST CDS_LIB mstr_misc
J 0
(825 2350);
DISPLAY INVISIBLE (825 2350);
FORCEPROP 1 LAST COMMENT_BODY TRUE
J 0
(825 2350);
DISPLAY INVISIBLE (825 2350);
FORCEADD DNS..2
(800 3725);
PAINT RED (800 3725);
FORCEPROP 2 LAST CDS_LIB mstr_misc
J 0
(800 3725);
DISPLAY INVISIBLE (800 3725);
FORCEPROP 1 LAST COMMENT_BODY TRUE
J 0
(800 3725);
DISPLAY INVISIBLE (800 3725);
FORCEADD DNS..2
(3825 4775);
PAINT RED (3825 4775);
FORCEPROP 1 LAST COMMENT_BODY TRUE
J 0
(3825 4775);
DISPLAY INVISIBLE (3825 4775);
FORCEPROP 2 LAST CDS_LIB mstr_misc
J 0
(3825 4775);
DISPLAY INVISIBLE (3825 4775);
FORCEADD DNS..2
(3875 3400);
PAINT RED (3875 3400);
FORCEPROP 2 LAST CDS_LIB mstr_misc
J 0
(3875 3400);
DISPLAY INVISIBLE (3875 3400);
FORCEPROP 1 LAST COMMENT_BODY TRUE
J 0
(3875 3400);
DISPLAY INVISIBLE (3875 3400);
FORCEADD DNS..2
(3800 1950);
PAINT RED (3800 1950);
FORCEPROP 1 LAST COMMENT_BODY TRUE
J 0
(3800 1950);
DISPLAY INVISIBLE (3800 1950);
FORCEPROP 2 LAST CDS_LIB mstr_misc
J 0
(3800 1950);
DISPLAY INVISIBLE (3800 1950);
FORCEADD DNS..2
(-825 1650);
PAINT RED (-825 1650);
FORCEPROP 1 LAST COMMENT_BODY TRUE
J 0
(-825 1650);
DISPLAY INVISIBLE (-825 1650);
FORCEPROP 2 LAST CDS_LIB mstr_misc
J 0
(-825 1650);
DISPLAY INVISIBLE (-825 1650);
FORCEADD DNS..2
(-825 3100);
PAINT RED (-825 3100);
FORCEPROP 1 LAST COMMENT_BODY TRUE
J 0
(-825 3100);
DISPLAY INVISIBLE (-825 3100);
FORCEPROP 2 LAST CDS_LIB mstr_misc
J 0
(-825 3100);
DISPLAY INVISIBLE (-825 3100);
FORCEADD DNS..2
(-700 4550);
PAINT RED (-700 4550);
FORCEPROP 1 LAST COMMENT_BODY TRUE
J 0
(-700 4550);
DISPLAY INVISIBLE (-700 4550);
FORCEPROP 2 LAST CDS_LIB mstr_misc
J 0
(-700 4550);
DISPLAY INVISIBLE (-700 4550);
WIRE 16 -1 (2350 2850)(2350 2750);
WIRE 16 -1 (-2225 -450)(-2225 -550);
WIRE 16 -1 (100 25)(100 -50);
WIRE 16 -1 (-1100 2900)(-1100 2825);
WIRE 16 -1 (3500 275)(3500 200);
WIRE 16 -1 (3525 3200)(3525 3125);
WIRE 16 -1 (3500 4575)(3500 4500);
WIRE 16 -1 (3500 1750)(3500 1675);
WIRE 16 -1 (4650 400)(4650 325);
WIRE 16 -1 (2325 -75)(2325 -175);
WIRE 16 -1 (4650 1875)(4650 1800);
WIRE 16 -1 (4675 3325)(4675 3250);
WIRE 16 -1 (-2300 3925)(-2300 3825);
WIRE 16 -1 (-1125 4275)(-1125 4200);
WIRE 16 -1 (4650 4700)(4650 4625);
WIRE 16 -1 (2325 4225)(2325 4125);
WIRE 16 -1 (25 4400)(25 4325);
WIRE 16 -1 (50 3025)(50 2950);
WIRE 16 -1 (-2300 1100)(-2300 1000);
WIRE 16 -1 (-2275 2550)(-2275 2450);
WIRE 16 -1 (25 1575)(25 1500);
WIRE 16 -1 (-1050 -100)(-1050 -175);
WIRE 16 -1 (2325 1400)(2325 1300);
WIRE 16 -1 (-1125 1450)(-1125 1375);
WIRE 16 -1 (5425 -350)(5425 -400);
WIRE 16 -1 (4650 -400)(4650 -525);
WIRE 16 -1 (3500 -700)(3500 -825);
WIRE 16 -1 (2350 -850)(2350 -975);
WIRE 16 -1 (2350 625)(2350 500);
WIRE 16 -1 (3500 775)(3500 650);
WIRE 16 -1 (4650 1075)(4650 950);
WIRE 16 -1 (5425 1125)(5425 1075);
WIRE 16 -1 (2350 3450)(2350 3325);
WIRE 16 -1 (2375 2075)(2375 1950);
WIRE 16 -1 (-2200 -1225)(-2200 -1350);
WIRE 16 -1 (-2275 325)(-2275 200);
WIRE 16 -1 (-2250 1775)(-2250 1650);
WIRE 16 -1 (-2275 3150)(-2275 3025);
WIRE 16 -1 (875 -725)(875 -775);
WIRE 16 -1 (100 -775)(100 -900);
WIRE 16 -1 (-1050 -1075)(-1050 -1200);
WIRE 16 -1 (-1125 475)(-1125 350);
WIRE 16 -1 (25 775)(25 650);
WIRE 16 -1 (800 825)(800 775);
WIRE 16 -1 (5425 3950)(5425 3900);
WIRE 16 -1 (5450 2575)(5450 2525);
WIRE 16 -1 (4675 2525)(4675 2400);
WIRE 16 -1 (4650 3900)(4650 3775);
WIRE 16 -1 (3500 3600)(3500 3475);
WIRE 16 -1 (3525 2225)(3525 2100);
WIRE 16 -1 (-1100 1925)(-1100 1800);
WIRE 16 -1 (-1125 3300)(-1125 3175);
WIRE 16 -1 (25 3600)(25 3475);
WIRE 16 -1 (50 2225)(50 2100);
WIRE 16 -1 (825 2275)(825 2225);
WIRE 16 -1 (800 3650)(800 3600);
WIRE 16 -1 (25 4050)(25 4000);
WIRE 16 -1 (25 4125)(25 4050);
WIRE 16 -1 (800 4050)(25 4050);
FORCEPROP 2 LAST SIG_NAME GPU_3V3IO_RSVD0_FFU_ISO
J 0
(90 4060);
DISPLAY 0.808511 (90 4060);
WIRE 16 -1 (800 3850)(800 4050);
WIRE 16 -1 (975 4050)(800 4050);
WIRE 16 -1 (1100 4050)(975 4050);
WIRE 16 -1 (975 4550)(975 4050);
WIRE 16 -1 (-625 4550)(975 4550);
WIRE 16 -1 (2325 3750)(2125 3750);
WIRE 16 -1 (2325 3925)(2325 3750);
WIRE 16 -1 (2350 3650)(2350 3750);
WIRE 16 -1 (2350 3750)(2325 3750);
WIRE 16 -1 (3175 3750)(2350 3750);
FORCEPROP 2 LAST SIG_NAME GPU_3V3IO_RSVD3_FFU
J 0
(2390 3760);
DISPLAY 0.808511 (2390 3760);
WIRE 16 -1 (3250 3750)(3175 3750);
WIRE 16 -1 (3175 4775)(3175 3750);
WIRE 16 -1 (3175 4775)(3700 4775);
WIRE 16 2175 (2150 2450)(2725 2450);
WIRE 16 2175 (2725 3025)(2725 2450);
WIRE 16 2175 (2150 3025)(2150 2450);
WIRE 16 2175 (2150 3025)(2725 3025);
WIRE 16 -1 (2350 2375)(2150 2375);
WIRE 16 -1 (2350 2550)(2350 2375);
WIRE 16 -1 (2375 2275)(2375 2375);
WIRE 16 -1 (2375 2375)(2350 2375);
WIRE 16 -1 (3225 2375)(2375 2375);
FORCEPROP 2 LAST SIG_NAME PRSNT_CABLE_GPU_A2_N
J 0
(2415 2385);
DISPLAY 0.808511 (2415 2385);
WIRE 16 -1 (3275 2375)(3225 2375);
WIRE 16 -1 (3225 3400)(3225 2375);
WIRE 16 -1 (3225 3400)(3750 3400);
WIRE 16 -1 (3150 1950)(3675 1950);
WIRE 16 -1 (3250 925)(3150 925);
WIRE 16 -1 (3150 1950)(3150 925);
WIRE 16 -1 (2350 825)(2350 925);
WIRE 16 -1 (3150 925)(2350 925);
FORCEPROP 2 LAST SIG_NAME GPU_3V3IO_RSVD5_FFU
J 0
(2390 935);
DISPLAY 0.808511 (2390 935);
WIRE 16 -1 (2325 925)(2125 925);
WIRE 16 -1 (2350 925)(2325 925);
WIRE 16 -1 (2325 1100)(2325 925);
WIRE 16 2175 (1775 -1075)(6125 -1075);
WIRE 16 2175 (6125 550)(6125 -1075);
WIRE 16 2175 (1775 550)(1775 -1075);
WIRE 16 2175 (1775 550)(6125 550);
WIRE 16 -1 (100 -325)(100 -375);
WIRE 16 -1 (100 -250)(100 -325);
WIRE 16 -1 (875 -325)(100 -325);
FORCEPROP 2 LAST SIG_NAME PRSNT_CABLE_GPU_A1_ISO_N
J 0
(165 -315);
DISPLAY 0.808511 (165 -315);
WIRE 16 -1 (875 -525)(875 -325);
WIRE 16 -1 (925 -325)(875 -325);
WIRE 16 -1 (1175 -325)(925 -325);
WIRE 16 -1 (-675 175)(925 175);
WIRE 16 -1 (925 175)(925 -325);
WIRE 16 2175 (-2550 700)(-1975 700);
WIRE 16 2175 (-1975 1275)(-1975 700);
WIRE 16 2175 (-2550 1275)(-2550 700);
WIRE 16 2175 (-2550 1275)(-1975 1275);
WIRE 16 2175 (-2400 -875)(-1825 -875);
WIRE 16 2175 (-1825 -300)(-1825 -875);
WIRE 16 2175 (-2400 -300)(-2400 -875);
WIRE 16 2175 (-2400 -300)(-1825 -300);
WIRE 16 -1 (-2300 625)(-2500 625);
WIRE 16 -1 (-2300 800)(-2300 625);
WIRE 16 -1 (-2275 525)(-2275 625);
WIRE 16 -1 (-2275 625)(-2300 625);
WIRE 16 -1 (-1475 625)(-2275 625);
FORCEPROP 2 LAST SIG_NAME PRSNT_CABLE_GPU_B3_N
J 0
(-2235 635);
DISPLAY 0.808511 (-2235 635);
WIRE 16 -1 (-1375 625)(-1475 625);
WIRE 16 -1 (-1475 1650)(-1475 625);
WIRE 16 -1 (-1475 1650)(-950 1650);
WIRE 16 -1 (25 1225)(25 1175);
WIRE 16 -1 (25 1300)(25 1225);
WIRE 16 -1 (-750 1650)(850 1650);
WIRE 16 -1 (800 1225)(25 1225);
FORCEPROP 2 LAST SIG_NAME PRSNT_CABLE_GPU_B3_ISO_N
J 0
(90 1235);
DISPLAY 0.808511 (90 1235);
WIRE 16 -1 (800 1025)(800 1225);
WIRE 16 -1 (850 1225)(800 1225);
WIRE 16 -1 (850 1650)(850 1225);
WIRE 16 -1 (1100 1225)(850 1225);
WIRE 16 -1 (-1400 175)(-875 175);
WIRE 16 -1 (-1300 -925)(-1400 -925);
WIRE 16 -1 (-1400 175)(-1400 -925);
WIRE 16 -1 (-2200 -1025)(-2200 -925);
WIRE 16 -1 (-1400 -925)(-2200 -925);
FORCEPROP 2 LAST SIG_NAME PRSNT_CABLE_GPU_A1_N
J 0
(-2160 -915);
DISPLAY 0.808511 (-2160 -915);
WIRE 16 -1 (-2225 -925)(-2200 -925);
WIRE 16 -1 (-2225 -750)(-2225 -925);
WIRE 16 -1 (-2425 -925)(-2225 -925);
WIRE 16 -1 (-1050 -375)(-1050 -625);
WIRE 16 -1 (-150 -625)(-1050 -625);
FORCEPROP 2 LAST SIG_NAME PRSNT_CABLE_GPU_A1
J 0
(-985 -615);
DISPLAY 0.808511 (-985 -615);
WIRE 16 -1 (-1050 -675)(-1050 -625);
WIRE 16 -1 (3950 3400)(5625 3400);
WIRE 16 -1 (5750 2975)(5625 2975);
WIRE 16 -1 (5625 3400)(5625 2975);
WIRE 16 -1 (5450 2775)(5450 2975);
WIRE 16 -1 (5625 2975)(5450 2975);
WIRE 16 -1 (4675 2975)(4675 2925);
WIRE 16 -1 (5450 2975)(4675 2975);
FORCEPROP 2 LAST SIG_NAME PRSNT_CABLE_GPU_A2_ISO_N
J 0
(4740 2985);
DISPLAY 0.808511 (4740 2985);
WIRE 16 -1 (4675 3050)(4675 2975);
WIRE 16 -1 (3525 2925)(3525 2675);
WIRE 16 -1 (4425 2675)(3525 2675);
FORCEPROP 2 LAST SIG_NAME PRSNT_CABLE_GPU_A2
J 0
(3590 2685);
DISPLAY 0.808511 (3590 2685);
WIRE 16 -1 (3525 2625)(3525 2675);
WIRE 16 -1 (4400 -250)(3500 -250);
FORCEPROP 2 LAST SIG_NAME SWB_HSC_PWRGD_N
J 0
(3565 -240);
DISPLAY 0.808511 (3565 -240);
WIRE 16 -1 (3500 0)(3500 -250);
WIRE 16 -1 (3500 -300)(3500 -250);
WIRE 16 -1 (-1475 4550)(-825 4550);
WIRE 16 -1 (-1375 3450)(-1475 3450);
WIRE 16 -1 (-1475 3450)(-1475 4550);
WIRE 16 -1 (-2275 3350)(-2275 3450);
WIRE 16 -1 (-1475 3450)(-2275 3450);
FORCEPROP 2 LAST SIG_NAME GPU_3V3IO_RSVD0_FFU
J 0
(-2235 3460);
DISPLAY 0.808511 (-2235 3460);
WIRE 16 -1 (-2300 3450)(-2500 3450);
WIRE 16 -1 (-2275 3450)(-2300 3450);
WIRE 16 -1 (-2300 3625)(-2300 3450);
WIRE 16 -1 (-1125 4000)(-1125 3750);
WIRE 16 -1 (-225 3750)(-1125 3750);
FORCEPROP 2 LAST SIG_NAME GPU_3V3IO_RSVD0_FFU_N
J 0
(-1060 3760);
DISPLAY 0.808511 (-1060 3760);
WIRE 16 -1 (-1125 3700)(-1125 3750);
WIRE 16 -1 (50 2675)(50 2625);
WIRE 16 -1 (50 2750)(50 2675);
WIRE 16 -1 (-750 3100)(850 3100);
WIRE 16 -1 (825 2675)(50 2675);
FORCEPROP 2 LAST SIG_NAME GPU_3V3IO_RSVD1_FFU_ISO
J 0
(115 2685);
DISPLAY 0.808511 (115 2685);
WIRE 16 -1 (825 2475)(825 2675);
WIRE 16 -1 (850 2675)(825 2675);
WIRE 16 -1 (850 3100)(850 2675);
WIRE 16 -1 (1125 2675)(850 2675);
WIRE 16 -1 (-1475 3100)(-950 3100);
WIRE 16 -1 (-1350 2075)(-1475 2075);
WIRE 16 -1 (-1475 3100)(-1475 2075);
WIRE 16 -1 (-2250 1975)(-2250 2075);
WIRE 16 -1 (-1475 2075)(-2250 2075);
FORCEPROP 2 LAST SIG_NAME GPU_3V3IO_RSVD1_FFU
J 0
(-2210 2085);
DISPLAY 0.808511 (-2210 2085);
WIRE 16 -1 (-2275 2075)(-2475 2075);
WIRE 16 -1 (-2250 2075)(-2275 2075);
WIRE 16 -1 (-2275 2250)(-2275 2075);
WIRE 16 -1 (4650 4350)(4650 4300);
WIRE 16 -1 (4650 4425)(4650 4350);
WIRE 16 -1 (3900 4775)(5500 4775);
WIRE 16 -1 (5425 4350)(4650 4350);
FORCEPROP 2 LAST SIG_NAME GPU_3V3IO_RSVD3_FFU_ISO
J 0
(4715 4360);
DISPLAY 0.808511 (4715 4360);
WIRE 16 -1 (5425 4150)(5425 4350);
WIRE 16 -1 (5500 4350)(5425 4350);
WIRE 16 -1 (5500 4775)(5500 4350);
WIRE 16 -1 (5725 4350)(5500 4350);
WIRE 16 -1 (4650 1525)(4650 1475);
WIRE 16 -1 (4650 1600)(4650 1525);
WIRE 16 -1 (3875 1950)(5600 1950);
WIRE 16 -1 (5425 1525)(4650 1525);
FORCEPROP 2 LAST SIG_NAME GPU_3V3IO_RSVD5_FFU_ISO
J 0
(4715 1535);
DISPLAY 0.808511 (4715 1535);
WIRE 16 -1 (5425 1325)(5425 1525);
WIRE 16 -1 (5600 1525)(5425 1525);
WIRE 16 -1 (5600 1950)(5600 1525);
WIRE 16 -1 (5725 1525)(5600 1525);
WIRE 16 -1 (3500 1475)(3500 1225);
WIRE 16 -1 (4400 1225)(3500 1225);
FORCEPROP 2 LAST SIG_NAME GPU_3V3IO_RSVD5_FFU_N
J 0
(3565 1235);
DISPLAY 0.808511 (3565 1235);
WIRE 16 -1 (3500 1175)(3500 1225);
WIRE 16 -1 (3500 4300)(3500 4050);
WIRE 16 -1 (4400 4050)(3500 4050);
FORCEPROP 2 LAST SIG_NAME GPU_3V3IO_RSVD3_FFU_N
J 0
(3565 4060);
DISPLAY 0.808511 (3565 4060);
WIRE 16 -1 (3500 4000)(3500 4050);
WIRE 16 -1 (-1100 2625)(-1100 2375);
WIRE 16 -1 (-200 2375)(-1100 2375);
FORCEPROP 2 LAST SIG_NAME GPU_3V3IO_RSVD1_FFU_N
J 0
(-1035 2385);
DISPLAY 0.808511 (-1035 2385);
WIRE 16 -1 (-1100 2325)(-1100 2375);
WIRE 16 -1 (-1125 1175)(-1125 925);
WIRE 16 -1 (-225 925)(-1125 925);
FORCEPROP 2 LAST SIG_NAME PRSNT_CABLE_GPU_B3
J 0
(-1060 935);
DISPLAY 0.808511 (-1060 935);
WIRE 16 -1 (-1125 875)(-1125 925);
WIRE 16 -1 (2350 -650)(2350 -550);
WIRE 16 -1 (3250 -550)(2350 -550);
FORCEPROP 2 LAST SIG_NAME SWB_HSC_PWRGD
J 0
(2365 -540);
DISPLAY 0.808511 (2365 -540);
WIRE 16 -1 (2325 -550)(2125 -550);
WIRE 16 -1 (2350 -550)(2325 -550);
WIRE 16 -1 (2325 -375)(2325 -550);
WIRE 16 -1 (4650 50)(4650 0);
WIRE 16 -1 (4650 125)(4650 50);
WIRE 16 -1 (5425 -150)(5425 50);
WIRE 16 -1 (5425 50)(4650 50);
FORCEPROP 2 LAST SIG_NAME SWB_HSC_PWRGD_ISO
J 0
(4865 60);
DISPLAY 0.808511 (4865 60);
WIRE 16 -1 (5725 50)(5425 50);
DOT 1 (3225 2375);
DOT 1 (25 1225);
DOT 1 (-2275 625);
DOT 1 (100 -325);
DOT 1 (5600 1525);
DOT 1 (3150 925);
DOT 1 (5625 2975);
DOT 1 (3175 3750);
DOT 1 (5500 4350);
DOT 1 (925 -325);
DOT 1 (-1475 625);
DOT 1 (850 1225);
DOT 1 (-1475 2075);
DOT 1 (850 2675);
DOT 1 (975 4050);
DOT 1 (-1475 3450);
DOT 1 (50 2675);
DOT 1 (2350 -550);
DOT 1 (2325 3750);
DOT 1 (-2275 2075);
DOT 1 (800 1225);
DOT 1 (-1125 925);
DOT 1 (-2300 625);
DOT 1 (-1050 -625);
DOT 1 (875 -325);
DOT 1 (5425 4350);
DOT 1 (4650 4350);
DOT 1 (5450 2975);
DOT 1 (4675 2975);
DOT 1 (3500 4050);
DOT 1 (3525 2675);
DOT 1 (2350 2375);
DOT 1 (-2300 3450);
DOT 1 (-1100 2375);
DOT 1 (-1125 3750);
DOT 1 (825 2675);
DOT 1 (25 4050);
DOT 1 (800 4050);
DOT 1 (-2275 3450);
DOT 1 (-2250 2075);
DOT 1 (-2200 -925);
DOT 1 (2375 2375);
DOT 1 (2350 3750);
DOT 1 (5425 50);
DOT 1 (4650 50);
DOT 1 (2325 -550);
DOT 1 (2325 925);
DOT 1 (3500 1225);
DOT 1 (4650 1525);
DOT 1 (5425 1525);
DOT 1 (3500 -250);
DOT 1 (2350 925);
DOT 1 (-1400 -925);
DOT 1 (-2225 -925);
FORCENOTE
20211130 CHANGE FOR GPU/BD RSVD PIN
(-2775 4725) 0;
DISPLAY LEFT (-2775 4725);
DISPLAY 2.106383 (-2775 4725);
PAINT WHITE (-2775 4725);
FORCENOTE
20220103 ADD SWB_HSC_PWRGD
(3200 -1150) 0;
DISPLAY LEFT (3200 -1150);
DISPLAY 1.276596 (3200 -1150);
PAINT PINK (3200 -1150);
FORCENOTE
20220802 CHANGE R4121 TO 10K OHM
(-2775 1325) 0;
DISPLAY LEFT (-2775 1325);
DISPLAY 0.808511 (-2775 1325);
PAINT PINK (-2775 1325);
FORCENOTE
20220802 CHANGE R4153 TO 10K OHM
(-2625 -250) 0;
DISPLAY LEFT (-2625 -250);
DISPLAY 0.808511 (-2625 -250);
PAINT PINK (-2625 -250);
FORCENOTE
20220802 CHANGE R4135 TO 10K OHM
(1925 3075) 0;
DISPLAY LEFT (1925 3075);
DISPLAY 0.808511 (1925 3075);
PAINT PINK (1925 3075);
QUIT
